FILE_TYPE = MACRO_DRAWING;
SET COLOR_WIRE YELLOW;
SET COLOR_PROP MONO;
SET COLOR_DOT WHITE;
SET COLOR_ARC YELLOW;
SET COLOR_BODY GREEN;
SET COLOR_NOTE MONO;
SET PROP_DISPLAY VALUE;
SET PAGE_NUMBER P67;
FORCEADD OFFPAGE..1
(-6700 3625);
FORCEPROP 2 LAST $XR0 33 
J 0
(-6951 3625);
DISPLAY 0.638298 (-6951 3625);
PAINT MONO (-6951 3625);
FORCEPROP 2 LAST CDS_LIB mstr_standard
J 0
(-6700 3625);
PAINT MONO (-6700 3625);
DISPLAY INVISIBLE (-6700 3625);
FORCEPROP 1 LAST OFFPAGE TRUE
J 0
(-6375 3500);
DISPLAY 1.170213 (-6375 3500);
PAINT GREEN (-6375 3500);
DISPLAY INVISIBLE (-6375 3500);
FORCEPROP 1 LAST COMMENT_BODY TRUE
J 0
(-6575 3525);
DISPLAY 1.170213 (-6575 3525);
PAINT GREEN (-6575 3525);
DISPLAY INVISIBLE (-6575 3525);
FORCEPROP 2 LAST PATH I1
J 0
(-6650 3700);
DISPLAY 1.021277 (-6650 3700);
PAINT ORANGE (-6650 3700);
DISPLAY INVISIBLE (-6650 3700);
FORCEADD TAP..1
R 2
(-5225 2125);
FORCEPROP 3 LASTPIN (-5175 2125) SIG_NAME UPI_CPU0_CPU1_P0P0_DP<11>
J 0
(-5165 2135);
DISPLAY 0.659574 (-5165 2135);
PAINT MONO (-5165 2135);
DISPLAY INVISIBLE (-5165 2135);
FORCEPROP 1 LASTPIN (-5175 2125) BN 11
J 2
(-5163 2133);
DISPLAY 0.617021 (-5163 2133);
PAINT GREEN (-5163 2133);
FORCEPROP 2 LAST CDS_LIB mstr_standard
J 0
(-5225 2125);
PAINT MONO (-5225 2125);
DISPLAY INVISIBLE (-5225 2125);
FORCEPROP 1 LAST BODY_TYPE PLUMBING
J 2
(-5225 2175);
DISPLAY 1.446809 (-5225 2175);
PAINT GREEN (-5225 2175);
DISPLAY INVISIBLE (-5225 2175);
FORCEPROP 1 LAST HDL_TAP TRUE
J 2
(-5550 2000);
DISPLAY 1.446809 (-5550 2000);
PAINT GREEN (-5550 2000);
DISPLAY INVISIBLE (-5550 2000);
FORCEPROP 1 LAST PATH I100
J 2
(-5223 2125);
DISPLAY 0.872340 (-5223 2125);
PAINT GREEN (-5223 2125);
DISPLAY INVISIBLE (-5223 2125);
FORCEADD TAP..1
R 2
(-5225 2025);
FORCEPROP 3 LASTPIN (-5175 2025) SIG_NAME UPI_CPU0_CPU1_P0P0_DP<9>
J 0
(-5165 2035);
DISPLAY 0.659574 (-5165 2035);
PAINT MONO (-5165 2035);
DISPLAY INVISIBLE (-5165 2035);
FORCEPROP 1 LASTPIN (-5175 2025) BN 9
J 2
(-5163 2033);
DISPLAY 0.617021 (-5163 2033);
PAINT GREEN (-5163 2033);
FORCEPROP 2 LAST CDS_LIB mstr_standard
J 0
(-5225 2025);
PAINT MONO (-5225 2025);
DISPLAY INVISIBLE (-5225 2025);
FORCEPROP 1 LAST BODY_TYPE PLUMBING
J 2
(-5225 2075);
DISPLAY 1.446809 (-5225 2075);
PAINT GREEN (-5225 2075);
DISPLAY INVISIBLE (-5225 2075);
FORCEPROP 1 LAST HDL_TAP TRUE
J 2
(-5550 1900);
DISPLAY 1.446809 (-5550 1900);
PAINT GREEN (-5550 1900);
DISPLAY INVISIBLE (-5550 1900);
FORCEPROP 1 LAST PATH I101
J 2
(-5223 2025);
DISPLAY 0.872340 (-5223 2025);
PAINT GREEN (-5223 2025);
DISPLAY INVISIBLE (-5223 2025);
FORCEADD TAP..1
R 2
(-5225 1975);
FORCEPROP 3 LASTPIN (-5175 1975) SIG_NAME UPI_CPU0_CPU1_P0P0_DP<8>
J 0
(-5165 1985);
DISPLAY 0.659574 (-5165 1985);
PAINT MONO (-5165 1985);
DISPLAY INVISIBLE (-5165 1985);
FORCEPROP 1 LASTPIN (-5175 1975) BN 8
J 2
(-5163 1983);
DISPLAY 0.617021 (-5163 1983);
PAINT GREEN (-5163 1983);
FORCEPROP 2 LAST CDS_LIB mstr_standard
J 0
(-5225 1975);
PAINT MONO (-5225 1975);
DISPLAY INVISIBLE (-5225 1975);
FORCEPROP 1 LAST BODY_TYPE PLUMBING
J 2
(-5225 2025);
DISPLAY 1.446809 (-5225 2025);
PAINT GREEN (-5225 2025);
DISPLAY INVISIBLE (-5225 2025);
FORCEPROP 1 LAST HDL_TAP TRUE
J 2
(-5550 1850);
DISPLAY 1.446809 (-5550 1850);
PAINT GREEN (-5550 1850);
DISPLAY INVISIBLE (-5550 1850);
FORCEPROP 1 LAST PATH I102
J 2
(-5223 1975);
DISPLAY 0.872340 (-5223 1975);
PAINT GREEN (-5223 1975);
DISPLAY INVISIBLE (-5223 1975);
FORCEADD TAP..1
R 2
(-5225 1925);
FORCEPROP 3 LASTPIN (-5175 1925) SIG_NAME UPI_CPU0_CPU1_P0P0_DP<7>
J 0
(-5165 1935);
DISPLAY 0.659574 (-5165 1935);
PAINT MONO (-5165 1935);
DISPLAY INVISIBLE (-5165 1935);
FORCEPROP 1 LASTPIN (-5175 1925) BN 7
J 2
(-5163 1933);
DISPLAY 0.617021 (-5163 1933);
PAINT GREEN (-5163 1933);
FORCEPROP 2 LAST CDS_LIB mstr_standard
J 0
(-5225 1925);
PAINT MONO (-5225 1925);
DISPLAY INVISIBLE (-5225 1925);
FORCEPROP 1 LAST BODY_TYPE PLUMBING
J 2
(-5225 1975);
DISPLAY 1.446809 (-5225 1975);
PAINT GREEN (-5225 1975);
DISPLAY INVISIBLE (-5225 1975);
FORCEPROP 1 LAST HDL_TAP TRUE
J 2
(-5550 1800);
DISPLAY 1.446809 (-5550 1800);
PAINT GREEN (-5550 1800);
DISPLAY INVISIBLE (-5550 1800);
FORCEPROP 1 LAST PATH I103
J 2
(-5223 1925);
DISPLAY 0.872340 (-5223 1925);
PAINT GREEN (-5223 1925);
DISPLAY INVISIBLE (-5223 1925);
FORCEADD TAP..1
R 2
(-5225 1875);
FORCEPROP 3 LASTPIN (-5175 1875) SIG_NAME UPI_CPU0_CPU1_P0P0_DP<6>
J 0
(-5165 1885);
DISPLAY 0.659574 (-5165 1885);
PAINT MONO (-5165 1885);
DISPLAY INVISIBLE (-5165 1885);
FORCEPROP 1 LASTPIN (-5175 1875) BN 6
J 2
(-5163 1883);
DISPLAY 0.617021 (-5163 1883);
PAINT GREEN (-5163 1883);
FORCEPROP 2 LAST CDS_LIB mstr_standard
J 0
(-5225 1875);
PAINT MONO (-5225 1875);
DISPLAY INVISIBLE (-5225 1875);
FORCEPROP 1 LAST BODY_TYPE PLUMBING
J 2
(-5225 1925);
DISPLAY 1.446809 (-5225 1925);
PAINT GREEN (-5225 1925);
DISPLAY INVISIBLE (-5225 1925);
FORCEPROP 1 LAST HDL_TAP TRUE
J 2
(-5550 1750);
DISPLAY 1.446809 (-5550 1750);
PAINT GREEN (-5550 1750);
DISPLAY INVISIBLE (-5550 1750);
FORCEPROP 1 LAST PATH I104
J 2
(-5223 1875);
DISPLAY 0.872340 (-5223 1875);
PAINT GREEN (-5223 1875);
DISPLAY INVISIBLE (-5223 1875);
FORCEADD TAP..1
R 2
(-5225 1825);
FORCEPROP 3 LASTPIN (-5175 1825) SIG_NAME UPI_CPU0_CPU1_P0P0_DP<5>
J 0
(-5165 1835);
DISPLAY 0.659574 (-5165 1835);
PAINT MONO (-5165 1835);
DISPLAY INVISIBLE (-5165 1835);
FORCEPROP 1 LASTPIN (-5175 1825) BN 5
J 2
(-5163 1833);
DISPLAY 0.617021 (-5163 1833);
PAINT GREEN (-5163 1833);
FORCEPROP 2 LAST CDS_LIB mstr_standard
J 0
(-5225 1825);
PAINT MONO (-5225 1825);
DISPLAY INVISIBLE (-5225 1825);
FORCEPROP 1 LAST BODY_TYPE PLUMBING
J 2
(-5225 1875);
DISPLAY 1.446809 (-5225 1875);
PAINT GREEN (-5225 1875);
DISPLAY INVISIBLE (-5225 1875);
FORCEPROP 1 LAST HDL_TAP TRUE
J 2
(-5550 1700);
DISPLAY 1.446809 (-5550 1700);
PAINT GREEN (-5550 1700);
DISPLAY INVISIBLE (-5550 1700);
FORCEPROP 1 LAST PATH I105
J 2
(-5223 1825);
DISPLAY 0.872340 (-5223 1825);
PAINT GREEN (-5223 1825);
DISPLAY INVISIBLE (-5223 1825);
FORCEADD TAP..1
R 2
(-5225 2675);
FORCEPROP 3 LASTPIN (-5175 2675) SIG_NAME UPI_CPU0_CPU1_P0P0_DP<1>
J 0
(-5165 2685);
DISPLAY 0.659574 (-5165 2685);
PAINT MONO (-5165 2685);
DISPLAY INVISIBLE (-5165 2685);
FORCEPROP 1 LASTPIN (-5175 2675) BN 1
J 2
(-5163 2683);
DISPLAY 0.617021 (-5163 2683);
PAINT GREEN (-5163 2683);
FORCEPROP 2 LAST CDS_LIB mstr_standard
J 0
(-5225 2675);
PAINT MONO (-5225 2675);
DISPLAY INVISIBLE (-5225 2675);
FORCEPROP 1 LAST BODY_TYPE PLUMBING
J 2
(-5225 2725);
DISPLAY 1.446809 (-5225 2725);
PAINT GREEN (-5225 2725);
DISPLAY INVISIBLE (-5225 2725);
FORCEPROP 1 LAST HDL_TAP TRUE
J 2
(-5550 2550);
DISPLAY 1.446809 (-5550 2550);
PAINT GREEN (-5550 2550);
DISPLAY INVISIBLE (-5550 2550);
FORCEPROP 1 LAST PATH I106
J 2
(-5223 2675);
DISPLAY 0.872340 (-5223 2675);
PAINT GREEN (-5223 2675);
DISPLAY INVISIBLE (-5223 2675);
FORCEADD TAP..1
R 2
(-5225 1575);
FORCEPROP 3 LASTPIN (-5175 1575) SIG_NAME UPI_CPU0_CPU1_P0P0_DP<0>
J 0
(-5165 1585);
DISPLAY 0.659574 (-5165 1585);
PAINT MONO (-5165 1585);
DISPLAY INVISIBLE (-5165 1585);
FORCEPROP 1 LASTPIN (-5175 1575) BN 0
J 2
(-5163 1583);
DISPLAY 0.617021 (-5163 1583);
PAINT GREEN (-5163 1583);
FORCEPROP 2 LAST CDS_LIB mstr_standard
J 0
(-5225 1575);
PAINT MONO (-5225 1575);
DISPLAY INVISIBLE (-5225 1575);
FORCEPROP 1 LAST BODY_TYPE PLUMBING
J 2
(-5225 1625);
DISPLAY 1.446809 (-5225 1625);
PAINT GREEN (-5225 1625);
DISPLAY INVISIBLE (-5225 1625);
FORCEPROP 1 LAST HDL_TAP TRUE
J 2
(-5550 1450);
DISPLAY 1.446809 (-5550 1450);
PAINT GREEN (-5550 1450);
DISPLAY INVISIBLE (-5550 1450);
FORCEPROP 1 LAST PATH I107
J 2
(-5223 1575);
DISPLAY 0.872340 (-5223 1575);
PAINT GREEN (-5223 1575);
DISPLAY INVISIBLE (-5223 1575);
FORCEADD TAP..1
R 2
(-5225 3275);
FORCEPROP 3 LASTPIN (-5175 3275) SIG_NAME UPI_CPU0_CPU1_P0P0_DP<13>
J 0
(-5165 3285);
DISPLAY 0.659574 (-5165 3285);
PAINT MONO (-5165 3285);
DISPLAY INVISIBLE (-5165 3285);
FORCEPROP 1 LASTPIN (-5175 3275) BN 13
J 2
(-5163 3283);
DISPLAY 0.617021 (-5163 3283);
PAINT GREEN (-5163 3283);
FORCEPROP 2 LAST CDS_LIB mstr_standard
J 0
(-5225 3275);
PAINT MONO (-5225 3275);
DISPLAY INVISIBLE (-5225 3275);
FORCEPROP 1 LAST BODY_TYPE PLUMBING
J 2
(-5225 3325);
DISPLAY 1.446809 (-5225 3325);
PAINT GREEN (-5225 3325);
DISPLAY INVISIBLE (-5225 3325);
FORCEPROP 1 LAST HDL_TAP TRUE
J 2
(-5550 3150);
DISPLAY 1.446809 (-5550 3150);
PAINT GREEN (-5550 3150);
DISPLAY INVISIBLE (-5550 3150);
FORCEPROP 1 LAST PATH I108
J 2
(-5223 3275);
DISPLAY 0.872340 (-5223 3275);
PAINT GREEN (-5223 3275);
DISPLAY INVISIBLE (-5223 3275);
FORCEADD TAP..1
(-2575 3575);
FORCEPROP 3 LASTPIN (-2625 3575) SIG_NAME UPI_CPU1_CPU0_P0P0_DN<19>
J 0
(-2615 3585);
DISPLAY 0.659574 (-2615 3585);
PAINT MONO (-2615 3585);
DISPLAY INVISIBLE (-2615 3585);
FORCEPROP 1 LASTPIN (-2625 3575) BN 19
J 0
(-2637 3583);
DISPLAY 0.617021 (-2637 3583);
PAINT GREEN (-2637 3583);
FORCEPROP 2 LAST CDS_LIB mstr_standard
J 2
(-2575 3575);
PAINT MONO (-2575 3575);
DISPLAY INVISIBLE (-2575 3575);
FORCEPROP 1 LAST BODY_TYPE PLUMBING
J 0
(-2575 3625);
DISPLAY 1.446809 (-2575 3625);
PAINT GREEN (-2575 3625);
DISPLAY INVISIBLE (-2575 3625);
FORCEPROP 1 LAST HDL_TAP TRUE
J 0
(-2250 3450);
DISPLAY 1.446809 (-2250 3450);
PAINT GREEN (-2250 3450);
DISPLAY INVISIBLE (-2250 3450);
FORCEPROP 1 LAST PATH I109
J 0
(-2577 3575);
DISPLAY 0.872340 (-2577 3575);
PAINT GREEN (-2577 3575);
DISPLAY INVISIBLE (-2577 3575);
FORCEADD TAP..1
(-2575 3425);
FORCEPROP 3 LASTPIN (-2625 3425) SIG_NAME UPI_CPU1_CPU0_P0P0_DN<16>
J 0
(-2615 3435);
DISPLAY 0.659574 (-2615 3435);
PAINT MONO (-2615 3435);
DISPLAY INVISIBLE (-2615 3435);
FORCEPROP 1 LASTPIN (-2625 3425) BN 16
J 0
(-2637 3433);
DISPLAY 0.617021 (-2637 3433);
PAINT GREEN (-2637 3433);
FORCEPROP 2 LAST CDS_LIB mstr_standard
J 0
(-2575 3425);
PAINT MONO (-2575 3425);
DISPLAY INVISIBLE (-2575 3425);
FORCEPROP 1 LAST BODY_TYPE PLUMBING
J 0
(-2575 3475);
DISPLAY 1.446809 (-2575 3475);
PAINT GREEN (-2575 3475);
DISPLAY INVISIBLE (-2575 3475);
FORCEPROP 1 LAST HDL_TAP TRUE
J 0
(-2250 3300);
DISPLAY 1.446809 (-2250 3300);
PAINT GREEN (-2250 3300);
DISPLAY INVISIBLE (-2250 3300);
FORCEPROP 1 LAST PATH I110
J 0
(-2577 3425);
DISPLAY 0.872340 (-2577 3425);
PAINT GREEN (-2577 3425);
DISPLAY INVISIBLE (-2577 3425);
FORCEADD TAP..1
(-2575 3375);
FORCEPROP 3 LASTPIN (-2625 3375) SIG_NAME UPI_CPU1_CPU0_P0P0_DN<15>
J 0
(-2615 3385);
DISPLAY 0.659574 (-2615 3385);
PAINT MONO (-2615 3385);
DISPLAY INVISIBLE (-2615 3385);
FORCEPROP 1 LASTPIN (-2625 3375) BN 15
J 0
(-2637 3383);
DISPLAY 0.617021 (-2637 3383);
PAINT GREEN (-2637 3383);
FORCEPROP 2 LAST CDS_LIB mstr_standard
J 0
(-2575 3375);
PAINT MONO (-2575 3375);
DISPLAY INVISIBLE (-2575 3375);
FORCEPROP 1 LAST BODY_TYPE PLUMBING
J 0
(-2575 3425);
DISPLAY 1.446809 (-2575 3425);
PAINT GREEN (-2575 3425);
DISPLAY INVISIBLE (-2575 3425);
FORCEPROP 1 LAST HDL_TAP TRUE
J 0
(-2250 3250);
DISPLAY 1.446809 (-2250 3250);
PAINT GREEN (-2250 3250);
DISPLAY INVISIBLE (-2250 3250);
FORCEPROP 1 LAST PATH I111
J 0
(-2577 3375);
DISPLAY 0.872340 (-2577 3375);
PAINT GREEN (-2577 3375);
DISPLAY INVISIBLE (-2577 3375);
FORCEADD TAP..1
(-2575 3275);
FORCEPROP 3 LASTPIN (-2625 3275) SIG_NAME UPI_CPU1_CPU0_P0P0_DN<13>
J 0
(-2615 3285);
DISPLAY 0.659574 (-2615 3285);
PAINT MONO (-2615 3285);
DISPLAY INVISIBLE (-2615 3285);
FORCEPROP 1 LASTPIN (-2625 3275) BN 13
J 0
(-2637 3283);
DISPLAY 0.617021 (-2637 3283);
PAINT GREEN (-2637 3283);
FORCEPROP 2 LAST CDS_LIB mstr_standard
J 0
(-2575 3275);
PAINT MONO (-2575 3275);
DISPLAY INVISIBLE (-2575 3275);
FORCEPROP 1 LAST BODY_TYPE PLUMBING
J 0
(-2575 3325);
DISPLAY 1.446809 (-2575 3325);
PAINT GREEN (-2575 3325);
DISPLAY INVISIBLE (-2575 3325);
FORCEPROP 1 LAST HDL_TAP TRUE
J 0
(-2250 3150);
DISPLAY 1.446809 (-2250 3150);
PAINT GREEN (-2250 3150);
DISPLAY INVISIBLE (-2250 3150);
FORCEPROP 1 LAST PATH I112
J 0
(-2577 3275);
DISPLAY 0.872340 (-2577 3275);
PAINT GREEN (-2577 3275);
DISPLAY INVISIBLE (-2577 3275);
FORCEADD TAP..1
(-2575 3225);
FORCEPROP 3 LASTPIN (-2625 3225) SIG_NAME UPI_CPU1_CPU0_P0P0_DN<12>
J 0
(-2615 3235);
DISPLAY 0.659574 (-2615 3235);
PAINT MONO (-2615 3235);
DISPLAY INVISIBLE (-2615 3235);
FORCEPROP 1 LASTPIN (-2625 3225) BN 12
J 0
(-2637 3233);
DISPLAY 0.617021 (-2637 3233);
PAINT GREEN (-2637 3233);
FORCEPROP 2 LAST CDS_LIB mstr_standard
J 0
(-2575 3225);
PAINT MONO (-2575 3225);
DISPLAY INVISIBLE (-2575 3225);
FORCEPROP 1 LAST BODY_TYPE PLUMBING
J 0
(-2575 3275);
DISPLAY 1.446809 (-2575 3275);
PAINT GREEN (-2575 3275);
DISPLAY INVISIBLE (-2575 3275);
FORCEPROP 1 LAST HDL_TAP TRUE
J 0
(-2250 3100);
DISPLAY 1.446809 (-2250 3100);
PAINT GREEN (-2250 3100);
DISPLAY INVISIBLE (-2250 3100);
FORCEPROP 1 LAST PATH I113
J 0
(-2577 3225);
DISPLAY 0.872340 (-2577 3225);
PAINT GREEN (-2577 3225);
DISPLAY INVISIBLE (-2577 3225);
FORCEADD TAP..1
(-2575 3175);
FORCEPROP 3 LASTPIN (-2625 3175) SIG_NAME UPI_CPU1_CPU0_P0P0_DN<11>
J 0
(-2615 3185);
DISPLAY 0.659574 (-2615 3185);
PAINT MONO (-2615 3185);
DISPLAY INVISIBLE (-2615 3185);
FORCEPROP 1 LASTPIN (-2625 3175) BN 11
J 0
(-2637 3183);
DISPLAY 0.617021 (-2637 3183);
PAINT GREEN (-2637 3183);
FORCEPROP 2 LAST CDS_LIB mstr_standard
J 0
(-2575 3175);
PAINT MONO (-2575 3175);
DISPLAY INVISIBLE (-2575 3175);
FORCEPROP 1 LAST BODY_TYPE PLUMBING
J 0
(-2575 3225);
DISPLAY 1.446809 (-2575 3225);
PAINT GREEN (-2575 3225);
DISPLAY INVISIBLE (-2575 3225);
FORCEPROP 1 LAST HDL_TAP TRUE
J 0
(-2250 3050);
DISPLAY 1.446809 (-2250 3050);
PAINT GREEN (-2250 3050);
DISPLAY INVISIBLE (-2250 3050);
FORCEPROP 1 LAST PATH I114
J 0
(-2577 3175);
DISPLAY 0.872340 (-2577 3175);
PAINT GREEN (-2577 3175);
DISPLAY INVISIBLE (-2577 3175);
FORCEADD TAP..1
(-2575 3025);
FORCEPROP 3 LASTPIN (-2625 3025) SIG_NAME UPI_CPU1_CPU0_P0P0_DN<8>
J 0
(-2615 3035);
DISPLAY 0.659574 (-2615 3035);
PAINT MONO (-2615 3035);
DISPLAY INVISIBLE (-2615 3035);
FORCEPROP 1 LASTPIN (-2625 3025) BN 8
J 0
(-2637 3033);
DISPLAY 0.617021 (-2637 3033);
PAINT GREEN (-2637 3033);
FORCEPROP 2 LAST CDS_LIB mstr_standard
J 0
(-2575 3025);
PAINT MONO (-2575 3025);
DISPLAY INVISIBLE (-2575 3025);
FORCEPROP 1 LAST BODY_TYPE PLUMBING
J 0
(-2575 3075);
DISPLAY 1.446809 (-2575 3075);
PAINT GREEN (-2575 3075);
DISPLAY INVISIBLE (-2575 3075);
FORCEPROP 1 LAST HDL_TAP TRUE
J 0
(-2250 2900);
DISPLAY 1.446809 (-2250 2900);
PAINT GREEN (-2250 2900);
DISPLAY INVISIBLE (-2250 2900);
FORCEPROP 1 LAST PATH I115
J 0
(-2577 3025);
DISPLAY 0.872340 (-2577 3025);
PAINT GREEN (-2577 3025);
DISPLAY INVISIBLE (-2577 3025);
FORCEADD TAP..1
(-2575 1875);
FORCEPROP 3 LASTPIN (-2625 1875) SIG_NAME UPI_CPU1_CPU0_P0P0_DN<6>
J 0
(-2615 1885);
DISPLAY 0.659574 (-2615 1885);
PAINT MONO (-2615 1885);
DISPLAY INVISIBLE (-2615 1885);
FORCEPROP 1 LASTPIN (-2625 1875) BN 6
J 0
(-2637 1883);
DISPLAY 0.617021 (-2637 1883);
PAINT GREEN (-2637 1883);
FORCEPROP 2 LAST CDS_LIB mstr_standard
J 0
(-2575 1875);
PAINT MONO (-2575 1875);
DISPLAY INVISIBLE (-2575 1875);
FORCEPROP 1 LAST BODY_TYPE PLUMBING
J 0
(-2575 1925);
DISPLAY 1.446809 (-2575 1925);
PAINT GREEN (-2575 1925);
DISPLAY INVISIBLE (-2575 1925);
FORCEPROP 1 LAST HDL_TAP TRUE
J 0
(-2250 1750);
DISPLAY 1.446809 (-2250 1750);
PAINT GREEN (-2250 1750);
DISPLAY INVISIBLE (-2250 1750);
FORCEPROP 1 LAST PATH I116
J 0
(-2577 1875);
DISPLAY 0.872340 (-2577 1875);
PAINT GREEN (-2577 1875);
DISPLAY INVISIBLE (-2577 1875);
FORCEADD TAP..1
(-2575 1775);
FORCEPROP 3 LASTPIN (-2625 1775) SIG_NAME UPI_CPU1_CPU0_P0P0_DN<4>
J 0
(-2615 1785);
DISPLAY 0.659574 (-2615 1785);
PAINT MONO (-2615 1785);
DISPLAY INVISIBLE (-2615 1785);
FORCEPROP 1 LASTPIN (-2625 1775) BN 4
J 0
(-2637 1783);
DISPLAY 0.617021 (-2637 1783);
PAINT GREEN (-2637 1783);
FORCEPROP 2 LAST CDS_LIB mstr_standard
J 0
(-2575 1775);
PAINT MONO (-2575 1775);
DISPLAY INVISIBLE (-2575 1775);
FORCEPROP 1 LAST BODY_TYPE PLUMBING
J 0
(-2575 1825);
DISPLAY 1.446809 (-2575 1825);
PAINT GREEN (-2575 1825);
DISPLAY INVISIBLE (-2575 1825);
FORCEPROP 1 LAST HDL_TAP TRUE
J 0
(-2250 1650);
DISPLAY 1.446809 (-2250 1650);
PAINT GREEN (-2250 1650);
DISPLAY INVISIBLE (-2250 1650);
FORCEPROP 1 LAST PATH I117
J 0
(-2577 1775);
DISPLAY 0.872340 (-2577 1775);
PAINT GREEN (-2577 1775);
DISPLAY INVISIBLE (-2577 1775);
FORCEADD TAP..1
(-2575 2675);
FORCEPROP 3 LASTPIN (-2625 2675) SIG_NAME UPI_CPU1_CPU0_P0P0_DN<1>
J 0
(-2615 2685);
DISPLAY 0.659574 (-2615 2685);
PAINT MONO (-2615 2685);
DISPLAY INVISIBLE (-2615 2685);
FORCEPROP 1 LASTPIN (-2625 2675) BN 1
J 0
(-2637 2683);
DISPLAY 0.617021 (-2637 2683);
PAINT GREEN (-2637 2683);
FORCEPROP 2 LAST CDS_LIB mstr_standard
J 0
(-2575 2675);
PAINT MONO (-2575 2675);
DISPLAY INVISIBLE (-2575 2675);
FORCEPROP 1 LAST BODY_TYPE PLUMBING
J 0
(-2575 2725);
DISPLAY 1.446809 (-2575 2725);
PAINT GREEN (-2575 2725);
DISPLAY INVISIBLE (-2575 2725);
FORCEPROP 1 LAST HDL_TAP TRUE
J 0
(-2250 2550);
DISPLAY 1.446809 (-2250 2550);
PAINT GREEN (-2250 2550);
DISPLAY INVISIBLE (-2250 2550);
FORCEPROP 1 LAST PATH I118
J 0
(-2577 2675);
DISPLAY 0.872340 (-2577 2675);
PAINT GREEN (-2577 2675);
DISPLAY INVISIBLE (-2577 2675);
FORCEADD TAP..1
(-2575 2625);
FORCEPROP 3 LASTPIN (-2625 2625) SIG_NAME UPI_CPU1_CPU0_P0P0_DN<0>
J 0
(-2615 2635);
DISPLAY 0.659574 (-2615 2635);
PAINT MONO (-2615 2635);
DISPLAY INVISIBLE (-2615 2635);
FORCEPROP 1 LASTPIN (-2625 2625) BN 0
J 0
(-2637 2633);
DISPLAY 0.617021 (-2637 2633);
PAINT GREEN (-2637 2633);
FORCEPROP 2 LAST CDS_LIB mstr_standard
J 0
(-2575 2625);
PAINT MONO (-2575 2625);
DISPLAY INVISIBLE (-2575 2625);
FORCEPROP 1 LAST BODY_TYPE PLUMBING
J 0
(-2575 2675);
DISPLAY 1.446809 (-2575 2675);
PAINT GREEN (-2575 2675);
DISPLAY INVISIBLE (-2575 2675);
FORCEPROP 1 LAST HDL_TAP TRUE
J 0
(-2250 2500);
DISPLAY 1.446809 (-2250 2500);
PAINT GREEN (-2250 2500);
DISPLAY INVISIBLE (-2250 2500);
FORCEPROP 1 LAST PATH I119
J 0
(-2577 2625);
DISPLAY 0.872340 (-2577 2625);
PAINT GREEN (-2577 2625);
DISPLAY INVISIBLE (-2577 2625);
FORCEADD TAP..1
(-2900 2525);
FORCEPROP 3 LASTPIN (-2950 2525) SIG_NAME UPI_CPU1_CPU0_P0P0_DP<19>
J 0
(-2940 2535);
DISPLAY 0.659574 (-2940 2535);
PAINT MONO (-2940 2535);
DISPLAY INVISIBLE (-2940 2535);
FORCEPROP 1 LASTPIN (-2950 2525) BN 19
J 0
(-2962 2533);
DISPLAY 0.617021 (-2962 2533);
PAINT GREEN (-2962 2533);
FORCEPROP 2 LAST CDS_LIB mstr_standard
J 0
(-2900 2525);
PAINT MONO (-2900 2525);
DISPLAY INVISIBLE (-2900 2525);
FORCEPROP 1 LAST BODY_TYPE PLUMBING
J 0
(-2900 2575);
DISPLAY 1.446809 (-2900 2575);
PAINT GREEN (-2900 2575);
DISPLAY INVISIBLE (-2900 2575);
FORCEPROP 1 LAST HDL_TAP TRUE
J 0
(-2575 2400);
DISPLAY 1.446809 (-2575 2400);
PAINT GREEN (-2575 2400);
DISPLAY INVISIBLE (-2575 2400);
FORCEPROP 1 LAST PATH I120
J 0
(-2902 2525);
DISPLAY 0.872340 (-2902 2525);
PAINT GREEN (-2902 2525);
DISPLAY INVISIBLE (-2902 2525);
FORCEADD TAP..1
(-2900 2375);
FORCEPROP 3 LASTPIN (-2950 2375) SIG_NAME UPI_CPU1_CPU0_P0P0_DP<16>
J 0
(-2940 2385);
DISPLAY 0.659574 (-2940 2385);
PAINT MONO (-2940 2385);
DISPLAY INVISIBLE (-2940 2385);
FORCEPROP 1 LASTPIN (-2950 2375) BN 16
J 0
(-2962 2383);
DISPLAY 0.617021 (-2962 2383);
PAINT GREEN (-2962 2383);
FORCEPROP 2 LAST CDS_LIB mstr_standard
J 0
(-2900 2375);
PAINT MONO (-2900 2375);
DISPLAY INVISIBLE (-2900 2375);
FORCEPROP 1 LAST BODY_TYPE PLUMBING
J 0
(-2900 2425);
DISPLAY 1.446809 (-2900 2425);
PAINT GREEN (-2900 2425);
DISPLAY INVISIBLE (-2900 2425);
FORCEPROP 1 LAST HDL_TAP TRUE
J 0
(-2575 2250);
DISPLAY 1.446809 (-2575 2250);
PAINT GREEN (-2575 2250);
DISPLAY INVISIBLE (-2575 2250);
FORCEPROP 1 LAST PATH I121
J 0
(-2902 2375);
DISPLAY 0.872340 (-2902 2375);
PAINT GREEN (-2902 2375);
DISPLAY INVISIBLE (-2902 2375);
FORCEADD TAP..1
(-2900 2325);
FORCEPROP 3 LASTPIN (-2950 2325) SIG_NAME UPI_CPU1_CPU0_P0P0_DP<15>
J 0
(-2940 2335);
DISPLAY 0.659574 (-2940 2335);
PAINT MONO (-2940 2335);
DISPLAY INVISIBLE (-2940 2335);
FORCEPROP 1 LASTPIN (-2950 2325) BN 15
J 0
(-2962 2333);
DISPLAY 0.617021 (-2962 2333);
PAINT GREEN (-2962 2333);
FORCEPROP 2 LAST CDS_LIB mstr_standard
J 0
(-2900 2325);
PAINT MONO (-2900 2325);
DISPLAY INVISIBLE (-2900 2325);
FORCEPROP 1 LAST BODY_TYPE PLUMBING
J 0
(-2900 2375);
DISPLAY 1.446809 (-2900 2375);
PAINT GREEN (-2900 2375);
DISPLAY INVISIBLE (-2900 2375);
FORCEPROP 1 LAST HDL_TAP TRUE
J 0
(-2575 2200);
DISPLAY 1.446809 (-2575 2200);
PAINT GREEN (-2575 2200);
DISPLAY INVISIBLE (-2575 2200);
FORCEPROP 1 LAST PATH I122
J 0
(-2902 2325);
DISPLAY 0.872340 (-2902 2325);
PAINT GREEN (-2902 2325);
DISPLAY INVISIBLE (-2902 2325);
FORCEADD TAP..1
(-2900 2225);
FORCEPROP 3 LASTPIN (-2950 2225) SIG_NAME UPI_CPU1_CPU0_P0P0_DP<13>
J 0
(-2940 2235);
DISPLAY 0.659574 (-2940 2235);
PAINT MONO (-2940 2235);
DISPLAY INVISIBLE (-2940 2235);
FORCEPROP 1 LASTPIN (-2950 2225) BN 13
J 0
(-2962 2233);
DISPLAY 0.617021 (-2962 2233);
PAINT GREEN (-2962 2233);
FORCEPROP 2 LAST CDS_LIB mstr_standard
J 0
(-2900 2225);
PAINT MONO (-2900 2225);
DISPLAY INVISIBLE (-2900 2225);
FORCEPROP 1 LAST BODY_TYPE PLUMBING
J 0
(-2900 2275);
DISPLAY 1.446809 (-2900 2275);
PAINT GREEN (-2900 2275);
DISPLAY INVISIBLE (-2900 2275);
FORCEPROP 1 LAST HDL_TAP TRUE
J 0
(-2575 2100);
DISPLAY 1.446809 (-2575 2100);
PAINT GREEN (-2575 2100);
DISPLAY INVISIBLE (-2575 2100);
FORCEPROP 1 LAST PATH I123
J 0
(-2902 2225);
DISPLAY 0.872340 (-2902 2225);
PAINT GREEN (-2902 2225);
DISPLAY INVISIBLE (-2902 2225);
FORCEADD TAP..1
(-2900 2175);
FORCEPROP 3 LASTPIN (-2950 2175) SIG_NAME UPI_CPU1_CPU0_P0P0_DP<12>
J 0
(-2940 2185);
DISPLAY 0.659574 (-2940 2185);
PAINT MONO (-2940 2185);
DISPLAY INVISIBLE (-2940 2185);
FORCEPROP 1 LASTPIN (-2950 2175) BN 12
J 0
(-2962 2183);
DISPLAY 0.617021 (-2962 2183);
PAINT GREEN (-2962 2183);
FORCEPROP 2 LAST CDS_LIB mstr_standard
J 0
(-2900 2175);
PAINT MONO (-2900 2175);
DISPLAY INVISIBLE (-2900 2175);
FORCEPROP 1 LAST BODY_TYPE PLUMBING
J 0
(-2900 2225);
DISPLAY 1.446809 (-2900 2225);
PAINT GREEN (-2900 2225);
DISPLAY INVISIBLE (-2900 2225);
FORCEPROP 1 LAST HDL_TAP TRUE
J 0
(-2575 2050);
DISPLAY 1.446809 (-2575 2050);
PAINT GREEN (-2575 2050);
DISPLAY INVISIBLE (-2575 2050);
FORCEPROP 1 LAST PATH I124
J 0
(-2902 2175);
DISPLAY 0.872340 (-2902 2175);
PAINT GREEN (-2902 2175);
DISPLAY INVISIBLE (-2902 2175);
FORCEADD TAP..1
(-2900 2125);
FORCEPROP 3 LASTPIN (-2950 2125) SIG_NAME UPI_CPU1_CPU0_P0P0_DP<11>
J 0
(-2940 2135);
DISPLAY 0.659574 (-2940 2135);
PAINT MONO (-2940 2135);
DISPLAY INVISIBLE (-2940 2135);
FORCEPROP 1 LASTPIN (-2950 2125) BN 11
J 0
(-2962 2133);
DISPLAY 0.617021 (-2962 2133);
PAINT GREEN (-2962 2133);
FORCEPROP 2 LAST CDS_LIB mstr_standard
J 0
(-2900 2125);
PAINT MONO (-2900 2125);
DISPLAY INVISIBLE (-2900 2125);
FORCEPROP 1 LAST BODY_TYPE PLUMBING
J 0
(-2900 2175);
DISPLAY 1.446809 (-2900 2175);
PAINT GREEN (-2900 2175);
DISPLAY INVISIBLE (-2900 2175);
FORCEPROP 1 LAST HDL_TAP TRUE
J 0
(-2575 2000);
DISPLAY 1.446809 (-2575 2000);
PAINT GREEN (-2575 2000);
DISPLAY INVISIBLE (-2575 2000);
FORCEPROP 1 LAST PATH I125
J 0
(-2902 2125);
DISPLAY 0.872340 (-2902 2125);
PAINT GREEN (-2902 2125);
DISPLAY INVISIBLE (-2902 2125);
FORCEADD TAP..1
(-2900 1975);
FORCEPROP 3 LASTPIN (-2950 1975) SIG_NAME UPI_CPU1_CPU0_P0P0_DP<8>
J 0
(-2940 1985);
DISPLAY 0.659574 (-2940 1985);
PAINT MONO (-2940 1985);
DISPLAY INVISIBLE (-2940 1985);
FORCEPROP 1 LASTPIN (-2950 1975) BN 8
J 0
(-2962 1983);
DISPLAY 0.617021 (-2962 1983);
PAINT GREEN (-2962 1983);
FORCEPROP 2 LAST CDS_LIB mstr_standard
J 0
(-2900 1975);
PAINT MONO (-2900 1975);
DISPLAY INVISIBLE (-2900 1975);
FORCEPROP 1 LAST BODY_TYPE PLUMBING
J 0
(-2900 2025);
DISPLAY 1.446809 (-2900 2025);
PAINT GREEN (-2900 2025);
DISPLAY INVISIBLE (-2900 2025);
FORCEPROP 1 LAST HDL_TAP TRUE
J 0
(-2575 1850);
DISPLAY 1.446809 (-2575 1850);
PAINT GREEN (-2575 1850);
DISPLAY INVISIBLE (-2575 1850);
FORCEPROP 1 LAST PATH I126
J 0
(-2902 1975);
DISPLAY 0.872340 (-2902 1975);
PAINT GREEN (-2902 1975);
DISPLAY INVISIBLE (-2902 1975);
FORCEADD TAP..1
(-2900 2925);
FORCEPROP 3 LASTPIN (-2950 2925) SIG_NAME UPI_CPU1_CPU0_P0P0_DP<6>
J 0
(-2940 2935);
DISPLAY 0.659574 (-2940 2935);
PAINT MONO (-2940 2935);
DISPLAY INVISIBLE (-2940 2935);
FORCEPROP 1 LASTPIN (-2950 2925) BN 6
J 0
(-2962 2933);
DISPLAY 0.617021 (-2962 2933);
PAINT GREEN (-2962 2933);
FORCEPROP 2 LAST CDS_LIB mstr_standard
J 0
(-2900 2925);
PAINT MONO (-2900 2925);
DISPLAY INVISIBLE (-2900 2925);
FORCEPROP 1 LAST BODY_TYPE PLUMBING
J 0
(-2900 2975);
DISPLAY 1.446809 (-2900 2975);
PAINT GREEN (-2900 2975);
DISPLAY INVISIBLE (-2900 2975);
FORCEPROP 1 LAST HDL_TAP TRUE
J 0
(-2575 2800);
DISPLAY 1.446809 (-2575 2800);
PAINT GREEN (-2575 2800);
DISPLAY INVISIBLE (-2575 2800);
FORCEPROP 1 LAST PATH I127
J 0
(-2902 2925);
DISPLAY 0.872340 (-2902 2925);
PAINT GREEN (-2902 2925);
DISPLAY INVISIBLE (-2902 2925);
FORCEADD TAP..1
(-2900 2825);
FORCEPROP 3 LASTPIN (-2950 2825) SIG_NAME UPI_CPU1_CPU0_P0P0_DP<4>
J 0
(-2940 2835);
DISPLAY 0.659574 (-2940 2835);
PAINT MONO (-2940 2835);
DISPLAY INVISIBLE (-2940 2835);
FORCEPROP 1 LASTPIN (-2950 2825) BN 4
J 0
(-2962 2833);
DISPLAY 0.617021 (-2962 2833);
PAINT GREEN (-2962 2833);
FORCEPROP 2 LAST CDS_LIB mstr_standard
J 0
(-2900 2825);
PAINT MONO (-2900 2825);
DISPLAY INVISIBLE (-2900 2825);
FORCEPROP 1 LAST BODY_TYPE PLUMBING
J 0
(-2900 2875);
DISPLAY 1.446809 (-2900 2875);
PAINT GREEN (-2900 2875);
DISPLAY INVISIBLE (-2900 2875);
FORCEPROP 1 LAST HDL_TAP TRUE
J 0
(-2575 2700);
DISPLAY 1.446809 (-2575 2700);
PAINT GREEN (-2575 2700);
DISPLAY INVISIBLE (-2575 2700);
FORCEPROP 1 LAST PATH I128
J 0
(-2902 2825);
DISPLAY 0.872340 (-2902 2825);
PAINT GREEN (-2902 2825);
DISPLAY INVISIBLE (-2902 2825);
FORCEADD TAP..1
(-2900 1625);
FORCEPROP 3 LASTPIN (-2950 1625) SIG_NAME UPI_CPU1_CPU0_P0P0_DP<1>
J 0
(-2940 1635);
DISPLAY 0.659574 (-2940 1635);
PAINT MONO (-2940 1635);
DISPLAY INVISIBLE (-2940 1635);
FORCEPROP 1 LASTPIN (-2950 1625) BN 1
J 0
(-2962 1633);
DISPLAY 0.617021 (-2962 1633);
PAINT GREEN (-2962 1633);
FORCEPROP 2 LAST CDS_LIB mstr_standard
J 0
(-2900 1625);
PAINT MONO (-2900 1625);
DISPLAY INVISIBLE (-2900 1625);
FORCEPROP 1 LAST BODY_TYPE PLUMBING
J 0
(-2900 1675);
DISPLAY 1.446809 (-2900 1675);
PAINT GREEN (-2900 1675);
DISPLAY INVISIBLE (-2900 1675);
FORCEPROP 1 LAST HDL_TAP TRUE
J 0
(-2575 1500);
DISPLAY 1.446809 (-2575 1500);
PAINT GREEN (-2575 1500);
DISPLAY INVISIBLE (-2575 1500);
FORCEPROP 1 LAST PATH I129
J 0
(-2902 1625);
DISPLAY 0.872340 (-2902 1625);
PAINT GREEN (-2902 1625);
DISPLAY INVISIBLE (-2902 1625);
FORCEADD TAP..1
(-2900 1575);
FORCEPROP 3 LASTPIN (-2950 1575) SIG_NAME UPI_CPU1_CPU0_P0P0_DP<0>
J 0
(-2940 1585);
DISPLAY 0.659574 (-2940 1585);
PAINT MONO (-2940 1585);
DISPLAY INVISIBLE (-2940 1585);
FORCEPROP 1 LASTPIN (-2950 1575) BN 0
J 0
(-2962 1583);
DISPLAY 0.617021 (-2962 1583);
PAINT GREEN (-2962 1583);
FORCEPROP 2 LAST CDS_LIB mstr_standard
J 0
(-2900 1575);
PAINT MONO (-2900 1575);
DISPLAY INVISIBLE (-2900 1575);
FORCEPROP 1 LAST BODY_TYPE PLUMBING
J 0
(-2900 1625);
DISPLAY 1.446809 (-2900 1625);
PAINT GREEN (-2900 1625);
DISPLAY INVISIBLE (-2900 1625);
FORCEPROP 1 LAST HDL_TAP TRUE
J 0
(-2575 1450);
DISPLAY 1.446809 (-2575 1450);
PAINT GREEN (-2575 1450);
DISPLAY INVISIBLE (-2575 1450);
FORCEPROP 1 LAST PATH I130
J 0
(-2902 1575);
DISPLAY 0.872340 (-2902 1575);
PAINT GREEN (-2902 1575);
DISPLAY INVISIBLE (-2902 1575);
FORCEADD TAP..1
R 2
(-5500 1625);
FORCEPROP 3 LASTPIN (-5450 1625) SIG_NAME UPI_CPU0_CPU1_P0P0_DN<1>
J 0
(-5440 1635);
DISPLAY 0.659574 (-5440 1635);
PAINT MONO (-5440 1635);
DISPLAY INVISIBLE (-5440 1635);
FORCEPROP 1 LASTPIN (-5450 1625) BN 1
J 2
(-5438 1633);
DISPLAY 0.617021 (-5438 1633);
PAINT GREEN (-5438 1633);
FORCEPROP 2 LAST CDS_LIB mstr_standard
J 0
(-5500 1625);
PAINT MONO (-5500 1625);
DISPLAY INVISIBLE (-5500 1625);
FORCEPROP 1 LAST BODY_TYPE PLUMBING
J 2
(-5500 1675);
DISPLAY 1.446809 (-5500 1675);
PAINT GREEN (-5500 1675);
DISPLAY INVISIBLE (-5500 1675);
FORCEPROP 1 LAST HDL_TAP TRUE
J 2
(-5825 1500);
DISPLAY 1.446809 (-5825 1500);
PAINT GREEN (-5825 1500);
DISPLAY INVISIBLE (-5825 1500);
FORCEPROP 1 LAST PATH I131
J 2
(-5498 1625);
DISPLAY 0.872340 (-5498 1625);
PAINT GREEN (-5498 1625);
DISPLAY INVISIBLE (-5498 1625);
FORCEADD SKX_EXT_B..13
(-4050 2575);
FORCEPROP 1 LAST LOCATION U2D1
J 0
(-4800 3825);
DISPLAY 0.617021 (-4800 3825);
PAINT AQUA (-4800 3825);
FORCEPROP 1 LAST PART_NUMBER TBD
J 0
(-4800 1375);
DISPLAY 0.617021 (-4800 1375);
PAINT BLUE (-4800 1375);
FORCEPROP 1 LAST MATERIAL IC
J 0
(-4800 3775);
DISPLAY 0.617021 (-4800 3775);
PAINT SKYBLUE (-4800 3775);
FORCEPROP 2 LASTPIN (-3250 3575) $PN BH3
J 0
(-3240 3585);
DISPLAY 0.617021 (-3240 3585);
PAINT ORANGE (-3240 3585);
FORCEPROP 2 LASTPIN (-3250 3525) $PN BD3
J 0
(-3240 3535);
DISPLAY 0.617021 (-3240 3535);
PAINT ORANGE (-3240 3535);
FORCEPROP 2 LASTPIN (-3250 3475) $PN BC2
J 0
(-3240 3485);
DISPLAY 0.617021 (-3240 3485);
PAINT ORANGE (-3240 3485);
FORCEPROP 2 LASTPIN (-3250 3425) $PN AY3
J 0
(-3240 3435);
DISPLAY 0.617021 (-3240 3435);
PAINT ORANGE (-3240 3435);
FORCEPROP 2 LASTPIN (-3250 3375) $PN AW4
J 0
(-3240 3385);
DISPLAY 0.617021 (-3240 3385);
PAINT ORANGE (-3240 3385);
FORCEPROP 2 LASTPIN (-3250 3325) $PN AR4
J 0
(-3240 3335);
DISPLAY 0.617021 (-3240 3335);
PAINT ORANGE (-3240 3335);
FORCEPROP 2 LASTPIN (-3250 3275) $PN AR2
J 0
(-3240 3285);
DISPLAY 0.617021 (-3240 3285);
PAINT ORANGE (-3240 3285);
FORCEPROP 2 LASTPIN (-3250 3225) $PN AP1
J 0
(-3240 3235);
DISPLAY 0.617021 (-3240 3235);
PAINT ORANGE (-3240 3235);
FORCEPROP 2 LASTPIN (-3250 3175) $PN AP3
J 0
(-3240 3185);
DISPLAY 0.617021 (-3240 3185);
PAINT ORANGE (-3240 3185);
FORCEPROP 2 LASTPIN (-3250 3125) $PN AK3
J 0
(-3240 3135);
DISPLAY 0.617021 (-3240 3135);
PAINT ORANGE (-3240 3135);
FORCEPROP 2 LASTPIN (-3250 3075) $PN AK1
J 0
(-3240 3085);
DISPLAY 0.617021 (-3240 3085);
PAINT ORANGE (-3240 3085);
FORCEPROP 2 LASTPIN (-3250 3025) $PN AJ2
J 0
(-3240 3035);
DISPLAY 0.617021 (-3240 3035);
PAINT ORANGE (-3240 3035);
FORCEPROP 2 LASTPIN (-3250 2975) $PN AG2
J 0
(-3240 2985);
DISPLAY 0.617021 (-3240 2985);
PAINT ORANGE (-3240 2985);
FORCEPROP 2 LASTPIN (-3250 2925) $PN AF3
J 0
(-3240 2935);
DISPLAY 0.617021 (-3240 2935);
PAINT ORANGE (-3240 2935);
FORCEPROP 2 LASTPIN (-3250 2875) $PN AD1
J 0
(-3240 2885);
DISPLAY 0.617021 (-3240 2885);
PAINT ORANGE (-3240 2885);
FORCEPROP 2 LASTPIN (-3250 2825) $PN AA2
J 0
(-3240 2835);
DISPLAY 0.617021 (-3240 2835);
PAINT ORANGE (-3240 2835);
FORCEPROP 2 LASTPIN (-3250 2775) $PN W2
J 0
(-3240 2785);
DISPLAY 0.617021 (-3240 2785);
PAINT ORANGE (-3240 2785);
FORCEPROP 2 LASTPIN (-3250 2725) $PN Y3
J 0
(-3240 2735);
DISPLAY 0.617021 (-3240 2735);
PAINT ORANGE (-3240 2735);
FORCEPROP 2 LASTPIN (-3250 2675) $PN T1
J 0
(-3240 2685);
DISPLAY 0.617021 (-3240 2685);
PAINT ORANGE (-3240 2685);
FORCEPROP 2 LASTPIN (-3250 2625) $PN M1
J 0
(-3240 2635);
DISPLAY 0.617021 (-3240 2635);
PAINT ORANGE (-3240 2635);
FORCEPROP 2 LASTPIN (-3250 2525) $PN BG4
J 0
(-3240 2535);
DISPLAY 0.617021 (-3240 2535);
PAINT ORANGE (-3240 2535);
FORCEPROP 2 LASTPIN (-3250 2475) $PN BF3
J 0
(-3240 2485);
DISPLAY 0.617021 (-3240 2485);
PAINT ORANGE (-3240 2485);
FORCEPROP 2 LASTPIN (-3250 2425) $PN BB3
J 0
(-3240 2435);
DISPLAY 0.617021 (-3240 2435);
PAINT ORANGE (-3240 2435);
FORCEPROP 2 LASTPIN (-3250 2375) $PN BA4
J 0
(-3240 2385);
DISPLAY 0.617021 (-3240 2385);
PAINT ORANGE (-3240 2385);
FORCEPROP 2 LASTPIN (-3250 2325) $PN AV5
J 0
(-3240 2335);
DISPLAY 0.617021 (-3240 2335);
PAINT ORANGE (-3240 2335);
FORCEPROP 2 LASTPIN (-3250 2275) $PN AU4
J 0
(-3240 2285);
DISPLAY 0.617021 (-3240 2285);
PAINT ORANGE (-3240 2285);
FORCEPROP 2 LASTPIN (-3250 2225) $PN AT3
J 0
(-3240 2235);
DISPLAY 0.617021 (-3240 2235);
PAINT ORANGE (-3240 2235);
FORCEPROP 2 LASTPIN (-3250 2175) $PN AT1
J 0
(-3240 2185);
DISPLAY 0.617021 (-3240 2185);
PAINT ORANGE (-3240 2185);
FORCEPROP 2 LASTPIN (-3250 2125) $PN AN4
J 0
(-3240 2135);
DISPLAY 0.617021 (-3240 2135);
PAINT ORANGE (-3240 2135);
FORCEPROP 2 LASTPIN (-3250 2075) $PN AM3
J 0
(-3240 2085);
DISPLAY 0.617021 (-3240 2085);
PAINT ORANGE (-3240 2085);
FORCEPROP 2 LASTPIN (-3250 2025) $PN AL2
J 0
(-3240 2035);
DISPLAY 0.617021 (-3240 2035);
PAINT ORANGE (-3240 2035);
FORCEPROP 2 LASTPIN (-3250 1975) $PN AH3
J 0
(-3240 1985);
DISPLAY 0.617021 (-3240 1985);
PAINT ORANGE (-3240 1985);
FORCEPROP 2 LASTPIN (-3250 1925) $PN AE2
J 0
(-3240 1935);
DISPLAY 0.617021 (-3240 1935);
PAINT ORANGE (-3240 1935);
FORCEPROP 2 LASTPIN (-3250 1875) $PN AG4
J 0
(-3240 1885);
DISPLAY 0.617021 (-3240 1885);
PAINT ORANGE (-3240 1885);
FORCEPROP 2 LASTPIN (-3250 1825) $PN AC2
J 0
(-3240 1835);
DISPLAY 0.617021 (-3240 1835);
PAINT ORANGE (-3240 1835);
FORCEPROP 2 LASTPIN (-3250 1775) $PN AB3
J 0
(-3240 1785);
DISPLAY 0.617021 (-3240 1785);
PAINT ORANGE (-3240 1785);
FORCEPROP 2 LASTPIN (-3250 1725) $PN Y1
J 0
(-3240 1735);
DISPLAY 0.617021 (-3240 1735);
PAINT ORANGE (-3240 1735);
FORCEPROP 2 LASTPIN (-3250 1675) $PN V3
J 0
(-3240 1685);
DISPLAY 0.617021 (-3240 1685);
PAINT ORANGE (-3240 1685);
FORCEPROP 2 LASTPIN (-3250 1625) $PN P1
J 0
(-3240 1635);
DISPLAY 0.617021 (-3240 1635);
PAINT ORANGE (-3240 1635);
FORCEPROP 2 LASTPIN (-3250 1575) $PN N2
J 0
(-3240 1585);
DISPLAY 0.617021 (-3240 1585);
PAINT ORANGE (-3240 1585);
FORCEPROP 2 LASTPIN (-4850 3575) $PN BA10
J 2
(-4860 3585);
DISPLAY 0.617021 (-4860 3585);
PAINT ORANGE (-4860 3585);
FORCEPROP 2 LASTPIN (-4850 3525) $PN BC10
J 2
(-4860 3535);
DISPLAY 0.617021 (-4860 3535);
PAINT ORANGE (-4860 3535);
FORCEPROP 2 LASTPIN (-4850 3475) $PN BB9
J 2
(-4860 3485);
DISPLAY 0.617021 (-4860 3485);
PAINT ORANGE (-4860 3485);
FORCEPROP 2 LASTPIN (-4850 3425) $PN AV9
J 2
(-4860 3435);
DISPLAY 0.617021 (-4860 3435);
PAINT ORANGE (-4860 3435);
FORCEPROP 2 LASTPIN (-4850 3375) $PN BF7
J 2
(-4860 3385);
DISPLAY 0.617021 (-4860 3385);
PAINT ORANGE (-4860 3385);
FORCEPROP 2 LASTPIN (-4850 3325) $PN BB7
J 2
(-4860 3335);
DISPLAY 0.617021 (-4860 3335);
PAINT ORANGE (-4860 3335);
FORCEPROP 2 LASTPIN (-4850 3275) $PN AY7
J 2
(-4860 3285);
DISPLAY 0.617021 (-4860 3285);
PAINT ORANGE (-4860 3285);
FORCEPROP 2 LASTPIN (-4850 3225) $PN AT9
J 2
(-4860 3235);
DISPLAY 0.617021 (-4860 3235);
PAINT ORANGE (-4860 3235);
FORCEPROP 2 LASTPIN (-4850 3175) $PN AU8
J 2
(-4860 3185);
DISPLAY 0.617021 (-4860 3185);
PAINT ORANGE (-4860 3185);
FORCEPROP 2 LASTPIN (-4850 3125) $PN AN8
J 2
(-4860 3135);
DISPLAY 0.617021 (-4860 3135);
PAINT ORANGE (-4860 3135);
FORCEPROP 2 LASTPIN (-4850 3075) $PN AL8
J 2
(-4860 3085);
DISPLAY 0.617021 (-4860 3085);
PAINT ORANGE (-4860 3085);
FORCEPROP 2 LASTPIN (-4850 3025) $PN AM7
J 2
(-4860 3035);
DISPLAY 0.617021 (-4860 3035);
PAINT ORANGE (-4860 3035);
FORCEPROP 2 LASTPIN (-4850 2975) $PN AK5
J 2
(-4860 2985);
DISPLAY 0.617021 (-4860 2985);
PAINT ORANGE (-4860 2985);
FORCEPROP 2 LASTPIN (-4850 2925) $PN AH7
J 2
(-4860 2935);
DISPLAY 0.617021 (-4860 2935);
PAINT ORANGE (-4860 2935);
FORCEPROP 2 LASTPIN (-4850 2875) $PN AF7
J 2
(-4860 2885);
DISPLAY 0.617021 (-4860 2885);
PAINT ORANGE (-4860 2885);
FORCEPROP 2 LASTPIN (-4850 2825) $PN AG6
J 2
(-4860 2835);
DISPLAY 0.617021 (-4860 2835);
PAINT ORANGE (-4860 2835);
FORCEPROP 2 LASTPIN (-4850 2775) $PN AC6
J 2
(-4860 2785);
DISPLAY 0.617021 (-4860 2785);
PAINT ORANGE (-4860 2785);
FORCEPROP 2 LASTPIN (-4850 2725) $PN AA6
J 2
(-4860 2735);
DISPLAY 0.617021 (-4860 2735);
PAINT ORANGE (-4860 2735);
FORCEPROP 2 LASTPIN (-4850 2675) $PN AC8
J 2
(-4860 2685);
DISPLAY 0.617021 (-4860 2685);
PAINT ORANGE (-4860 2685);
FORCEPROP 2 LASTPIN (-4850 2625) $PN AB9
J 2
(-4860 2635);
DISPLAY 0.617021 (-4860 2635);
PAINT ORANGE (-4860 2635);
FORCEPROP 2 LASTPIN (-4850 2525) $PN BB11
J 2
(-4860 2535);
DISPLAY 0.617021 (-4860 2535);
PAINT ORANGE (-4860 2535);
FORCEPROP 2 LASTPIN (-4850 2475) $PN BD9
J 2
(-4860 2485);
DISPLAY 0.617021 (-4860 2485);
PAINT ORANGE (-4860 2485);
FORCEPROP 2 LASTPIN (-4850 2425) $PN AY9
J 2
(-4860 2435);
DISPLAY 0.617021 (-4860 2435);
PAINT ORANGE (-4860 2435);
FORCEPROP 2 LASTPIN (-4850 2375) $PN AW8
J 2
(-4860 2385);
DISPLAY 0.617021 (-4860 2385);
PAINT ORANGE (-4860 2385);
FORCEPROP 2 LASTPIN (-4850 2325) $PN BD7
J 2
(-4860 2335);
DISPLAY 0.617021 (-4860 2335);
PAINT ORANGE (-4860 2335);
FORCEPROP 2 LASTPIN (-4850 2275) $PN BC6
J 2
(-4860 2285);
DISPLAY 0.617021 (-4860 2285);
PAINT ORANGE (-4860 2285);
FORCEPROP 2 LASTPIN (-4850 2225) $PN BA8
J 2
(-4860 2235);
DISPLAY 0.617021 (-4860 2235);
PAINT ORANGE (-4860 2235);
FORCEPROP 2 LASTPIN (-4850 2175) $PN AU10
J 2
(-4860 2185);
DISPLAY 0.617021 (-4860 2185);
PAINT ORANGE (-4860 2185);
FORCEPROP 2 LASTPIN (-4850 2125) $PN AR8
J 2
(-4860 2135);
DISPLAY 0.617021 (-4860 2135);
PAINT ORANGE (-4860 2135);
FORCEPROP 2 LASTPIN (-4850 2075) $PN AP7
J 2
(-4860 2085);
DISPLAY 0.617021 (-4860 2085);
PAINT ORANGE (-4860 2085);
FORCEPROP 2 LASTPIN (-4850 2025) $PN AM9
J 2
(-4860 2035);
DISPLAY 0.617021 (-4860 2035);
PAINT ORANGE (-4860 2035);
FORCEPROP 2 LASTPIN (-4850 1975) $PN AK7
J 2
(-4860 1985);
DISPLAY 0.617021 (-4860 1985);
PAINT ORANGE (-4860 1985);
FORCEPROP 2 LASTPIN (-4850 1925) $PN AL6
J 2
(-4860 1935);
DISPLAY 0.617021 (-4860 1935);
PAINT ORANGE (-4860 1935);
FORCEPROP 2 LASTPIN (-4850 1875) $PN AJ6
J 2
(-4860 1885);
DISPLAY 0.617021 (-4860 1885);
PAINT ORANGE (-4860 1885);
FORCEPROP 2 LASTPIN (-4850 1825) $PN AG8
J 2
(-4860 1835);
DISPLAY 0.617021 (-4860 1835);
PAINT ORANGE (-4860 1835);
FORCEPROP 2 LASTPIN (-4850 1775) $PN AE6
J 2
(-4860 1785);
DISPLAY 0.617021 (-4860 1785);
PAINT ORANGE (-4860 1785);
FORCEPROP 2 LASTPIN (-4850 1725) $PN AD5
J 2
(-4860 1735);
DISPLAY 0.617021 (-4860 1735);
PAINT ORANGE (-4860 1735);
FORCEPROP 2 LASTPIN (-4850 1675) $PN AB7
J 2
(-4860 1685);
DISPLAY 0.617021 (-4860 1685);
PAINT ORANGE (-4860 1685);
FORCEPROP 2 LASTPIN (-4850 1625) $PN AA8
J 2
(-4860 1635);
DISPLAY 0.617021 (-4860 1635);
PAINT ORANGE (-4860 1635);
FORCEPROP 2 LASTPIN (-4850 1575) $PN AC10
J 2
(-4860 1585);
DISPLAY 0.617021 (-4860 1585);
PAINT ORANGE (-4860 1585);
FORCEPROP 1 LAST PACK_TYPE BGA1
J 0
(-4800 3875);
PAINT SKYBLUE (-4800 3875);
DISPLAY INVISIBLE (-4800 3875);
FORCEPROP 2 LAST SEC_TYPE BGA1
J 0
(-4800 3875);
DISPLAY 1.021277 (-4800 3875);
PAINT ORANGE (-4800 3875);
DISPLAY INVISIBLE (-4800 3875);
FORCEPROP 2 LAST CDS_LIB chpset_lib
J 0
(-4050 2575);
PAINT ORANGE (-4050 2575);
DISPLAY INVISIBLE (-4050 2575);
FORCEPROP 2 LAST SEC 13
J 0
(-4800 3875);
DISPLAY 0.680851 (-4800 3875);
PAINT MONO (-4800 3875);
DISPLAY INVISIBLE (-4800 3875);
FORCEPROP 2 LAST CDS_LOCATION U2D1
J 0
(-4800 3825);
DISPLAY 0.617021 (-4800 3825);
PAINT AQUA (-4800 3825);
DISPLAY INVISIBLE (-4800 3825);
FORCEPROP 1 LAST PATH I132
J 0
(-4050 3775);
PAINT GREEN (-4050 3775);
DISPLAY INVISIBLE (-4050 3775);
FORCEADD TAP..1
R 2
(-5500 2075);
FORCEPROP 3 LASTPIN (-5450 2075) SIG_NAME UPI_CPU0_CPU1_P0P0_DN<10>
J 0
(-5440 2085);
DISPLAY 0.659574 (-5440 2085);
PAINT MONO (-5440 2085);
DISPLAY INVISIBLE (-5440 2085);
FORCEPROP 1 LASTPIN (-5450 2075) BN 10
J 2
(-5438 2083);
DISPLAY 0.617021 (-5438 2083);
PAINT GREEN (-5438 2083);
FORCEPROP 2 LAST CDS_LIB mstr_standard
J 0
(-5500 2075);
PAINT MONO (-5500 2075);
DISPLAY INVISIBLE (-5500 2075);
FORCEPROP 1 LAST BODY_TYPE PLUMBING
J 2
(-5500 2125);
DISPLAY 1.446809 (-5500 2125);
PAINT GREEN (-5500 2125);
DISPLAY INVISIBLE (-5500 2125);
FORCEPROP 1 LAST HDL_TAP TRUE
J 2
(-5825 1950);
DISPLAY 1.446809 (-5825 1950);
PAINT GREEN (-5825 1950);
DISPLAY INVISIBLE (-5825 1950);
FORCEPROP 1 LAST PATH I14
J 2
(-5498 2075);
DISPLAY 0.872340 (-5498 2075);
PAINT GREEN (-5498 2075);
DISPLAY INVISIBLE (-5498 2075);
FORCEADD TAP..1
R 2
(-5500 2175);
FORCEPROP 3 LASTPIN (-5450 2175) SIG_NAME UPI_CPU0_CPU1_P0P0_DN<12>
J 0
(-5440 2185);
DISPLAY 0.659574 (-5440 2185);
PAINT MONO (-5440 2185);
DISPLAY INVISIBLE (-5440 2185);
FORCEPROP 1 LASTPIN (-5450 2175) BN 12
J 2
(-5438 2183);
DISPLAY 0.617021 (-5438 2183);
PAINT GREEN (-5438 2183);
FORCEPROP 2 LAST CDS_LIB mstr_standard
J 0
(-5500 2175);
PAINT MONO (-5500 2175);
DISPLAY INVISIBLE (-5500 2175);
FORCEPROP 1 LAST BODY_TYPE PLUMBING
J 2
(-5500 2225);
DISPLAY 1.446809 (-5500 2225);
PAINT GREEN (-5500 2225);
DISPLAY INVISIBLE (-5500 2225);
FORCEPROP 1 LAST HDL_TAP TRUE
J 2
(-5825 2050);
DISPLAY 1.446809 (-5825 2050);
PAINT GREEN (-5825 2050);
DISPLAY INVISIBLE (-5825 2050);
FORCEPROP 1 LAST PATH I16
J 2
(-5498 2175);
DISPLAY 0.872340 (-5498 2175);
PAINT GREEN (-5498 2175);
DISPLAY INVISIBLE (-5498 2175);
FORCEADD OFFPAGE..1
(-6700 3700);
FORCEPROP 2 LAST $XR0 33 
J 0
(-6951 3700);
DISPLAY 0.638298 (-6951 3700);
PAINT MONO (-6951 3700);
FORCEPROP 2 LAST CDS_LIB mstr_standard
J 0
(-6700 3700);
PAINT MONO (-6700 3700);
DISPLAY INVISIBLE (-6700 3700);
FORCEPROP 1 LAST OFFPAGE TRUE
J 0
(-6375 3575);
DISPLAY 1.170213 (-6375 3575);
PAINT GREEN (-6375 3575);
DISPLAY INVISIBLE (-6375 3575);
FORCEPROP 1 LAST COMMENT_BODY TRUE
J 0
(-6575 3600);
DISPLAY 1.170213 (-6575 3600);
PAINT GREEN (-6575 3600);
DISPLAY INVISIBLE (-6575 3600);
FORCEPROP 2 LAST PATH I2
J 0
(-6650 3775);
DISPLAY 1.021277 (-6650 3775);
PAINT ORANGE (-6650 3775);
DISPLAY INVISIBLE (-6650 3775);
FORCEADD TAP..1
R 2
(-5500 2375);
FORCEPROP 3 LASTPIN (-5450 2375) SIG_NAME UPI_CPU0_CPU1_P0P0_DN<16>
J 0
(-5440 2385);
DISPLAY 0.659574 (-5440 2385);
PAINT MONO (-5440 2385);
DISPLAY INVISIBLE (-5440 2385);
FORCEPROP 1 LASTPIN (-5450 2375) BN 16
J 2
(-5438 2383);
DISPLAY 0.617021 (-5438 2383);
PAINT GREEN (-5438 2383);
FORCEPROP 2 LAST CDS_LIB mstr_standard
J 0
(-5500 2375);
PAINT MONO (-5500 2375);
DISPLAY INVISIBLE (-5500 2375);
FORCEPROP 1 LAST BODY_TYPE PLUMBING
J 2
(-5500 2425);
DISPLAY 1.446809 (-5500 2425);
PAINT GREEN (-5500 2425);
DISPLAY INVISIBLE (-5500 2425);
FORCEPROP 1 LAST HDL_TAP TRUE
J 2
(-5825 2250);
DISPLAY 1.446809 (-5825 2250);
PAINT GREEN (-5825 2250);
DISPLAY INVISIBLE (-5825 2250);
FORCEPROP 1 LAST PATH I20
J 2
(-5498 2375);
DISPLAY 0.872340 (-5498 2375);
PAINT GREEN (-5498 2375);
DISPLAY INVISIBLE (-5498 2375);
FORCEADD TAP..1
R 2
(-5500 2425);
FORCEPROP 3 LASTPIN (-5450 2425) SIG_NAME UPI_CPU0_CPU1_P0P0_DN<17>
J 0
(-5440 2435);
DISPLAY 0.659574 (-5440 2435);
PAINT MONO (-5440 2435);
DISPLAY INVISIBLE (-5440 2435);
FORCEPROP 1 LASTPIN (-5450 2425) BN 17
J 2
(-5438 2433);
DISPLAY 0.617021 (-5438 2433);
PAINT GREEN (-5438 2433);
FORCEPROP 2 LAST CDS_LIB mstr_standard
J 0
(-5500 2425);
PAINT MONO (-5500 2425);
DISPLAY INVISIBLE (-5500 2425);
FORCEPROP 1 LAST BODY_TYPE PLUMBING
J 2
(-5500 2475);
DISPLAY 1.446809 (-5500 2475);
PAINT GREEN (-5500 2475);
DISPLAY INVISIBLE (-5500 2475);
FORCEPROP 1 LAST HDL_TAP TRUE
J 2
(-5825 2300);
DISPLAY 1.446809 (-5825 2300);
PAINT GREEN (-5825 2300);
DISPLAY INVISIBLE (-5825 2300);
FORCEPROP 1 LAST PATH I21
J 2
(-5498 2425);
DISPLAY 0.872340 (-5498 2425);
PAINT GREEN (-5498 2425);
DISPLAY INVISIBLE (-5498 2425);
FORCEADD TAP..1
R 2
(-5225 2725);
FORCEPROP 3 LASTPIN (-5175 2725) SIG_NAME UPI_CPU0_CPU1_P0P0_DP<2>
J 0
(-5165 2735);
DISPLAY 0.659574 (-5165 2735);
PAINT MONO (-5165 2735);
DISPLAY INVISIBLE (-5165 2735);
FORCEPROP 1 LASTPIN (-5175 2725) BN 2
J 2
(-5163 2733);
DISPLAY 0.617021 (-5163 2733);
PAINT GREEN (-5163 2733);
FORCEPROP 2 LAST CDS_LIB mstr_standard
J 0
(-5225 2725);
PAINT MONO (-5225 2725);
DISPLAY INVISIBLE (-5225 2725);
FORCEPROP 1 LAST BODY_TYPE PLUMBING
J 2
(-5225 2775);
DISPLAY 1.446809 (-5225 2775);
PAINT GREEN (-5225 2775);
DISPLAY INVISIBLE (-5225 2775);
FORCEPROP 1 LAST HDL_TAP TRUE
J 2
(-5550 2600);
DISPLAY 1.446809 (-5550 2600);
PAINT GREEN (-5550 2600);
DISPLAY INVISIBLE (-5550 2600);
FORCEPROP 1 LAST PATH I26
J 2
(-5223 2725);
DISPLAY 0.872340 (-5223 2725);
PAINT GREEN (-5223 2725);
DISPLAY INVISIBLE (-5223 2725);
FORCEADD TAP..1
R 2
(-5225 1725);
FORCEPROP 3 LASTPIN (-5175 1725) SIG_NAME UPI_CPU0_CPU1_P0P0_DP<3>
J 0
(-5165 1735);
DISPLAY 0.659574 (-5165 1735);
PAINT MONO (-5165 1735);
DISPLAY INVISIBLE (-5165 1735);
FORCEPROP 1 LASTPIN (-5175 1725) BN 3
J 2
(-5163 1733);
DISPLAY 0.617021 (-5163 1733);
PAINT GREEN (-5163 1733);
FORCEPROP 2 LAST CDS_LIB mstr_standard
J 0
(-5225 1725);
PAINT MONO (-5225 1725);
DISPLAY INVISIBLE (-5225 1725);
FORCEPROP 1 LAST BODY_TYPE PLUMBING
J 2
(-5225 1775);
DISPLAY 1.446809 (-5225 1775);
PAINT GREEN (-5225 1775);
DISPLAY INVISIBLE (-5225 1775);
FORCEPROP 1 LAST HDL_TAP TRUE
J 2
(-5550 1600);
DISPLAY 1.446809 (-5550 1600);
PAINT GREEN (-5550 1600);
DISPLAY INVISIBLE (-5550 1600);
FORCEPROP 1 LAST PATH I27
J 2
(-5223 1725);
DISPLAY 0.872340 (-5223 1725);
PAINT GREEN (-5223 1725);
DISPLAY INVISIBLE (-5223 1725);
FORCEADD TAP..1
R 2
(-5225 1775);
FORCEPROP 3 LASTPIN (-5175 1775) SIG_NAME UPI_CPU0_CPU1_P0P0_DP<4>
J 0
(-5165 1785);
DISPLAY 0.659574 (-5165 1785);
PAINT MONO (-5165 1785);
DISPLAY INVISIBLE (-5165 1785);
FORCEPROP 1 LASTPIN (-5175 1775) BN 4
J 2
(-5163 1783);
DISPLAY 0.617021 (-5163 1783);
PAINT GREEN (-5163 1783);
FORCEPROP 2 LAST CDS_LIB mstr_standard
J 0
(-5225 1775);
PAINT MONO (-5225 1775);
DISPLAY INVISIBLE (-5225 1775);
FORCEPROP 1 LAST BODY_TYPE PLUMBING
J 2
(-5225 1825);
DISPLAY 1.446809 (-5225 1825);
PAINT GREEN (-5225 1825);
DISPLAY INVISIBLE (-5225 1825);
FORCEPROP 1 LAST HDL_TAP TRUE
J 2
(-5550 1650);
DISPLAY 1.446809 (-5550 1650);
PAINT GREEN (-5550 1650);
DISPLAY INVISIBLE (-5550 1650);
FORCEPROP 1 LAST PATH I28
J 2
(-5223 1775);
DISPLAY 0.872340 (-5223 1775);
PAINT GREEN (-5223 1775);
DISPLAY INVISIBLE (-5223 1775);
FORCEADD TAP..1
R 2
(-5225 3125);
FORCEPROP 3 LASTPIN (-5175 3125) SIG_NAME UPI_CPU0_CPU1_P0P0_DP<10>
J 0
(-5165 3135);
DISPLAY 0.659574 (-5165 3135);
PAINT MONO (-5165 3135);
DISPLAY INVISIBLE (-5165 3135);
FORCEPROP 1 LASTPIN (-5175 3125) BN 10
J 2
(-5163 3133);
DISPLAY 0.617021 (-5163 3133);
PAINT GREEN (-5163 3133);
FORCEPROP 2 LAST CDS_LIB mstr_standard
J 0
(-5225 3125);
PAINT MONO (-5225 3125);
DISPLAY INVISIBLE (-5225 3125);
FORCEPROP 1 LAST BODY_TYPE PLUMBING
J 2
(-5225 3175);
DISPLAY 1.446809 (-5225 3175);
PAINT GREEN (-5225 3175);
DISPLAY INVISIBLE (-5225 3175);
FORCEPROP 1 LAST HDL_TAP TRUE
J 2
(-5550 3000);
DISPLAY 1.446809 (-5550 3000);
PAINT GREEN (-5550 3000);
DISPLAY INVISIBLE (-5550 3000);
FORCEPROP 1 LAST PATH I34
J 2
(-5223 3125);
DISPLAY 0.872340 (-5223 3125);
PAINT GREEN (-5223 3125);
DISPLAY INVISIBLE (-5223 3125);
FORCEADD TAP..1
R 2
(-5225 3225);
FORCEPROP 3 LASTPIN (-5175 3225) SIG_NAME UPI_CPU0_CPU1_P0P0_DP<12>
J 0
(-5165 3235);
DISPLAY 0.659574 (-5165 3235);
PAINT MONO (-5165 3235);
DISPLAY INVISIBLE (-5165 3235);
FORCEPROP 1 LASTPIN (-5175 3225) BN 12
J 2
(-5163 3233);
DISPLAY 0.617021 (-5163 3233);
PAINT GREEN (-5163 3233);
FORCEPROP 2 LAST CDS_LIB mstr_standard
J 0
(-5225 3225);
PAINT MONO (-5225 3225);
DISPLAY INVISIBLE (-5225 3225);
FORCEPROP 1 LAST BODY_TYPE PLUMBING
J 2
(-5225 3275);
DISPLAY 1.446809 (-5225 3275);
PAINT GREEN (-5225 3275);
DISPLAY INVISIBLE (-5225 3275);
FORCEPROP 1 LAST HDL_TAP TRUE
J 2
(-5550 3100);
DISPLAY 1.446809 (-5550 3100);
PAINT GREEN (-5550 3100);
DISPLAY INVISIBLE (-5550 3100);
FORCEPROP 1 LAST PATH I36
J 2
(-5223 3225);
DISPLAY 0.872340 (-5223 3225);
PAINT GREEN (-5223 3225);
DISPLAY INVISIBLE (-5223 3225);
FORCEADD TAP..1
R 2
(-5225 3425);
FORCEPROP 3 LASTPIN (-5175 3425) SIG_NAME UPI_CPU0_CPU1_P0P0_DP<16>
J 0
(-5165 3435);
DISPLAY 0.659574 (-5165 3435);
PAINT MONO (-5165 3435);
DISPLAY INVISIBLE (-5165 3435);
FORCEPROP 1 LASTPIN (-5175 3425) BN 16
J 2
(-5163 3433);
DISPLAY 0.617021 (-5163 3433);
PAINT GREEN (-5163 3433);
FORCEPROP 2 LAST CDS_LIB mstr_standard
J 0
(-5225 3425);
PAINT MONO (-5225 3425);
DISPLAY INVISIBLE (-5225 3425);
FORCEPROP 1 LAST BODY_TYPE PLUMBING
J 2
(-5225 3475);
DISPLAY 1.446809 (-5225 3475);
PAINT GREEN (-5225 3475);
DISPLAY INVISIBLE (-5225 3475);
FORCEPROP 1 LAST HDL_TAP TRUE
J 2
(-5550 3300);
DISPLAY 1.446809 (-5550 3300);
PAINT GREEN (-5550 3300);
DISPLAY INVISIBLE (-5550 3300);
FORCEPROP 1 LAST PATH I40
J 2
(-5223 3425);
DISPLAY 0.872340 (-5223 3425);
PAINT GREEN (-5223 3425);
DISPLAY INVISIBLE (-5223 3425);
FORCEADD TAP..1
R 2
(-5225 3475);
FORCEPROP 3 LASTPIN (-5175 3475) SIG_NAME UPI_CPU0_CPU1_P0P0_DP<17>
J 0
(-5165 3485);
DISPLAY 0.659574 (-5165 3485);
PAINT MONO (-5165 3485);
DISPLAY INVISIBLE (-5165 3485);
FORCEPROP 1 LASTPIN (-5175 3475) BN 17
J 2
(-5163 3483);
DISPLAY 0.617021 (-5163 3483);
PAINT GREEN (-5163 3483);
FORCEPROP 2 LAST CDS_LIB mstr_standard
J 0
(-5225 3475);
PAINT MONO (-5225 3475);
DISPLAY INVISIBLE (-5225 3475);
FORCEPROP 1 LAST BODY_TYPE PLUMBING
J 2
(-5225 3525);
DISPLAY 1.446809 (-5225 3525);
PAINT GREEN (-5225 3525);
DISPLAY INVISIBLE (-5225 3525);
FORCEPROP 1 LAST HDL_TAP TRUE
J 2
(-5550 3350);
DISPLAY 1.446809 (-5550 3350);
PAINT GREEN (-5550 3350);
DISPLAY INVISIBLE (-5550 3350);
FORCEPROP 1 LAST PATH I41
J 2
(-5223 3475);
DISPLAY 0.872340 (-5223 3475);
PAINT GREEN (-5223 3475);
DISPLAY INVISIBLE (-5223 3475);
FORCEADD TAP..1
R 2
(-5225 2475);
FORCEPROP 3 LASTPIN (-5175 2475) SIG_NAME UPI_CPU0_CPU1_P0P0_DP<18>
J 0
(-5165 2485);
DISPLAY 0.659574 (-5165 2485);
PAINT MONO (-5165 2485);
DISPLAY INVISIBLE (-5165 2485);
FORCEPROP 1 LASTPIN (-5175 2475) BN 18
J 2
(-5163 2483);
DISPLAY 0.617021 (-5163 2483);
PAINT GREEN (-5163 2483);
FORCEPROP 2 LAST CDS_LIB mstr_standard
J 0
(-5225 2475);
PAINT MONO (-5225 2475);
DISPLAY INVISIBLE (-5225 2475);
FORCEPROP 1 LAST BODY_TYPE PLUMBING
J 2
(-5225 2525);
DISPLAY 1.446809 (-5225 2525);
PAINT GREEN (-5225 2525);
DISPLAY INVISIBLE (-5225 2525);
FORCEPROP 1 LAST HDL_TAP TRUE
J 2
(-5550 2350);
DISPLAY 1.446809 (-5550 2350);
PAINT GREEN (-5550 2350);
DISPLAY INVISIBLE (-5550 2350);
FORCEPROP 1 LAST PATH I42
J 2
(-5223 2475);
DISPLAY 0.872340 (-5223 2475);
PAINT GREEN (-5223 2475);
DISPLAY INVISIBLE (-5223 2475);
FORCEADD TAP..1
R 2
(-5225 2525);
FORCEPROP 3 LASTPIN (-5175 2525) SIG_NAME UPI_CPU0_CPU1_P0P0_DP<19>
J 0
(-5165 2535);
DISPLAY 0.659574 (-5165 2535);
PAINT MONO (-5165 2535);
DISPLAY INVISIBLE (-5165 2535);
FORCEPROP 1 LASTPIN (-5175 2525) BN 19
J 2
(-5163 2533);
DISPLAY 0.617021 (-5163 2533);
PAINT GREEN (-5163 2533);
FORCEPROP 2 LAST CDS_LIB mstr_standard
J 0
(-5225 2525);
PAINT MONO (-5225 2525);
DISPLAY INVISIBLE (-5225 2525);
FORCEPROP 1 LAST BODY_TYPE PLUMBING
J 2
(-5225 2575);
DISPLAY 1.446809 (-5225 2575);
PAINT GREEN (-5225 2575);
DISPLAY INVISIBLE (-5225 2575);
FORCEPROP 1 LAST HDL_TAP TRUE
J 2
(-5550 2400);
DISPLAY 1.446809 (-5550 2400);
PAINT GREEN (-5550 2400);
DISPLAY INVISIBLE (-5550 2400);
FORCEPROP 1 LAST PATH I43
J 2
(-5223 2525);
DISPLAY 0.872340 (-5223 2525);
PAINT GREEN (-5223 2525);
DISPLAY INVISIBLE (-5223 2525);
FORCEADD TAP..1
(-2575 1675);
FORCEPROP 3 LASTPIN (-2625 1675) SIG_NAME UPI_CPU1_CPU0_P0P0_DN<2>
J 0
(-2615 1685);
DISPLAY 0.659574 (-2615 1685);
PAINT MONO (-2615 1685);
DISPLAY INVISIBLE (-2615 1685);
FORCEPROP 1 LASTPIN (-2625 1675) BN 2
J 0
(-2637 1683);
DISPLAY 0.617021 (-2637 1683);
PAINT GREEN (-2637 1683);
FORCEPROP 2 LAST CDS_LIB mstr_standard
J 0
(-2575 1675);
PAINT MONO (-2575 1675);
DISPLAY INVISIBLE (-2575 1675);
FORCEPROP 1 LAST BODY_TYPE PLUMBING
J 0
(-2575 1725);
DISPLAY 1.446809 (-2575 1725);
PAINT GREEN (-2575 1725);
DISPLAY INVISIBLE (-2575 1725);
FORCEPROP 1 LAST HDL_TAP TRUE
J 0
(-2250 1550);
DISPLAY 1.446809 (-2250 1550);
PAINT GREEN (-2250 1550);
DISPLAY INVISIBLE (-2250 1550);
FORCEPROP 1 LAST PATH I46
J 0
(-2577 1675);
DISPLAY 0.872340 (-2577 1675);
PAINT GREEN (-2577 1675);
DISPLAY INVISIBLE (-2577 1675);
FORCEADD TAP..1
(-2575 1725);
FORCEPROP 3 LASTPIN (-2625 1725) SIG_NAME UPI_CPU1_CPU0_P0P0_DN<3>
J 0
(-2615 1735);
DISPLAY 0.659574 (-2615 1735);
PAINT MONO (-2615 1735);
DISPLAY INVISIBLE (-2615 1735);
FORCEPROP 1 LASTPIN (-2625 1725) BN 3
J 0
(-2637 1733);
DISPLAY 0.617021 (-2637 1733);
PAINT GREEN (-2637 1733);
FORCEPROP 2 LAST CDS_LIB mstr_standard
J 0
(-2575 1725);
PAINT MONO (-2575 1725);
DISPLAY INVISIBLE (-2575 1725);
FORCEPROP 1 LAST BODY_TYPE PLUMBING
J 0
(-2575 1775);
DISPLAY 1.446809 (-2575 1775);
PAINT GREEN (-2575 1775);
DISPLAY INVISIBLE (-2575 1775);
FORCEPROP 1 LAST HDL_TAP TRUE
J 0
(-2250 1600);
DISPLAY 1.446809 (-2250 1600);
PAINT GREEN (-2250 1600);
DISPLAY INVISIBLE (-2250 1600);
FORCEPROP 1 LAST PATH I48
J 0
(-2577 1725);
DISPLAY 0.872340 (-2577 1725);
PAINT GREEN (-2577 1725);
DISPLAY INVISIBLE (-2577 1725);
FORCEADD TAP..1
(-2575 2875);
FORCEPROP 3 LASTPIN (-2625 2875) SIG_NAME UPI_CPU1_CPU0_P0P0_DN<5>
J 0
(-2615 2885);
DISPLAY 0.659574 (-2615 2885);
PAINT MONO (-2615 2885);
DISPLAY INVISIBLE (-2615 2885);
FORCEPROP 1 LASTPIN (-2625 2875) BN 5
J 0
(-2637 2883);
DISPLAY 0.617021 (-2637 2883);
PAINT GREEN (-2637 2883);
FORCEPROP 2 LAST CDS_LIB mstr_standard
J 0
(-2575 2875);
PAINT MONO (-2575 2875);
DISPLAY INVISIBLE (-2575 2875);
FORCEPROP 1 LAST BODY_TYPE PLUMBING
J 0
(-2575 2925);
DISPLAY 1.446809 (-2575 2925);
PAINT GREEN (-2575 2925);
DISPLAY INVISIBLE (-2575 2925);
FORCEPROP 1 LAST HDL_TAP TRUE
J 0
(-2250 2750);
DISPLAY 1.446809 (-2250 2750);
PAINT GREEN (-2250 2750);
DISPLAY INVISIBLE (-2250 2750);
FORCEPROP 1 LAST PATH I49
J 0
(-2577 2875);
DISPLAY 0.872340 (-2577 2875);
PAINT GREEN (-2577 2875);
DISPLAY INVISIBLE (-2577 2875);
FORCEADD TAP..1
R 2
(-5500 1675);
FORCEPROP 3 LASTPIN (-5450 1675) SIG_NAME UPI_CPU0_CPU1_P0P0_DN<2>
J 0
(-5440 1685);
DISPLAY 0.659574 (-5440 1685);
PAINT MONO (-5440 1685);
DISPLAY INVISIBLE (-5440 1685);
FORCEPROP 1 LASTPIN (-5450 1675) BN 2
J 2
(-5438 1683);
DISPLAY 0.617021 (-5438 1683);
PAINT GREEN (-5438 1683);
FORCEPROP 2 LAST CDS_LIB mstr_standard
J 0
(-5500 1675);
PAINT MONO (-5500 1675);
DISPLAY INVISIBLE (-5500 1675);
FORCEPROP 1 LAST BODY_TYPE PLUMBING
J 2
(-5500 1725);
DISPLAY 1.446809 (-5500 1725);
PAINT GREEN (-5500 1725);
DISPLAY INVISIBLE (-5500 1725);
FORCEPROP 1 LAST HDL_TAP TRUE
J 2
(-5825 1550);
DISPLAY 1.446809 (-5825 1550);
PAINT GREEN (-5825 1550);
DISPLAY INVISIBLE (-5825 1550);
FORCEPROP 1 LAST PATH I5
J 2
(-5498 1675);
DISPLAY 0.872340 (-5498 1675);
PAINT GREEN (-5498 1675);
DISPLAY INVISIBLE (-5498 1675);
FORCEADD TAP..1
(-2575 1925);
FORCEPROP 3 LASTPIN (-2625 1925) SIG_NAME UPI_CPU1_CPU0_P0P0_DN<7>
J 0
(-2615 1935);
DISPLAY 0.659574 (-2615 1935);
PAINT MONO (-2615 1935);
DISPLAY INVISIBLE (-2615 1935);
FORCEPROP 1 LASTPIN (-2625 1925) BN 7
J 0
(-2637 1933);
DISPLAY 0.617021 (-2637 1933);
PAINT GREEN (-2637 1933);
FORCEPROP 2 LAST CDS_LIB mstr_standard
J 0
(-2575 1925);
PAINT MONO (-2575 1925);
DISPLAY INVISIBLE (-2575 1925);
FORCEPROP 1 LAST BODY_TYPE PLUMBING
J 0
(-2575 1975);
DISPLAY 1.446809 (-2575 1975);
PAINT GREEN (-2575 1975);
DISPLAY INVISIBLE (-2575 1975);
FORCEPROP 1 LAST HDL_TAP TRUE
J 0
(-2250 1800);
DISPLAY 1.446809 (-2250 1800);
PAINT GREEN (-2250 1800);
DISPLAY INVISIBLE (-2250 1800);
FORCEPROP 1 LAST PATH I51
J 0
(-2577 1925);
DISPLAY 0.872340 (-2577 1925);
PAINT GREEN (-2577 1925);
DISPLAY INVISIBLE (-2577 1925);
FORCEADD TAP..1
(-2575 3125);
FORCEPROP 3 LASTPIN (-2625 3125) SIG_NAME UPI_CPU1_CPU0_P0P0_DN<10>
J 0
(-2615 3135);
DISPLAY 0.659574 (-2615 3135);
PAINT MONO (-2615 3135);
DISPLAY INVISIBLE (-2615 3135);
FORCEPROP 1 LASTPIN (-2625 3125) BN 10
J 0
(-2637 3133);
DISPLAY 0.617021 (-2637 3133);
PAINT GREEN (-2637 3133);
FORCEPROP 2 LAST CDS_LIB mstr_standard
J 0
(-2575 3125);
PAINT MONO (-2575 3125);
DISPLAY INVISIBLE (-2575 3125);
FORCEPROP 1 LAST BODY_TYPE PLUMBING
J 0
(-2575 3175);
DISPLAY 1.446809 (-2575 3175);
PAINT GREEN (-2575 3175);
DISPLAY INVISIBLE (-2575 3175);
FORCEPROP 1 LAST HDL_TAP TRUE
J 0
(-2250 3000);
DISPLAY 1.446809 (-2250 3000);
PAINT GREEN (-2250 3000);
DISPLAY INVISIBLE (-2250 3000);
FORCEPROP 1 LAST PATH I53
J 0
(-2577 3125);
DISPLAY 0.872340 (-2577 3125);
PAINT GREEN (-2577 3125);
DISPLAY INVISIBLE (-2577 3125);
FORCEADD TAP..1
(-2575 2025);
FORCEPROP 3 LASTPIN (-2625 2025) SIG_NAME UPI_CPU1_CPU0_P0P0_DN<9>
J 0
(-2615 2035);
DISPLAY 0.659574 (-2615 2035);
PAINT MONO (-2615 2035);
DISPLAY INVISIBLE (-2615 2035);
FORCEPROP 1 LASTPIN (-2625 2025) BN 9
J 0
(-2637 2033);
DISPLAY 0.617021 (-2637 2033);
PAINT GREEN (-2637 2033);
FORCEPROP 2 LAST CDS_LIB mstr_standard
J 0
(-2575 2025);
PAINT MONO (-2575 2025);
DISPLAY INVISIBLE (-2575 2025);
FORCEPROP 1 LAST BODY_TYPE PLUMBING
J 0
(-2575 2075);
DISPLAY 1.446809 (-2575 2075);
PAINT GREEN (-2575 2075);
DISPLAY INVISIBLE (-2575 2075);
FORCEPROP 1 LAST HDL_TAP TRUE
J 0
(-2250 1900);
DISPLAY 1.446809 (-2250 1900);
PAINT GREEN (-2250 1900);
DISPLAY INVISIBLE (-2250 1900);
FORCEPROP 1 LAST PATH I54
J 0
(-2577 2025);
DISPLAY 0.872340 (-2577 2025);
PAINT GREEN (-2577 2025);
DISPLAY INVISIBLE (-2577 2025);
FORCEADD TAP..1
(-2575 3325);
FORCEPROP 3 LASTPIN (-2625 3325) SIG_NAME UPI_CPU1_CPU0_P0P0_DN<14>
J 0
(-2615 3335);
DISPLAY 0.659574 (-2615 3335);
PAINT MONO (-2615 3335);
DISPLAY INVISIBLE (-2615 3335);
FORCEPROP 1 LASTPIN (-2625 3325) BN 14
J 0
(-2637 3333);
DISPLAY 0.617021 (-2637 3333);
PAINT GREEN (-2637 3333);
FORCEPROP 2 LAST CDS_LIB mstr_standard
J 0
(-2575 3325);
PAINT MONO (-2575 3325);
DISPLAY INVISIBLE (-2575 3325);
FORCEPROP 1 LAST BODY_TYPE PLUMBING
J 0
(-2575 3375);
DISPLAY 1.446809 (-2575 3375);
PAINT GREEN (-2575 3375);
DISPLAY INVISIBLE (-2575 3375);
FORCEPROP 1 LAST HDL_TAP TRUE
J 0
(-2250 3200);
DISPLAY 1.446809 (-2250 3200);
PAINT GREEN (-2250 3200);
DISPLAY INVISIBLE (-2250 3200);
FORCEPROP 1 LAST PATH I58
J 0
(-2577 3325);
DISPLAY 0.872340 (-2577 3325);
PAINT GREEN (-2577 3325);
DISPLAY INVISIBLE (-2577 3325);
FORCEADD TAP..1
R 2
(-5500 2825);
FORCEPROP 3 LASTPIN (-5450 2825) SIG_NAME UPI_CPU0_CPU1_P0P0_DN<4>
J 0
(-5440 2835);
DISPLAY 0.659574 (-5440 2835);
PAINT MONO (-5440 2835);
DISPLAY INVISIBLE (-5440 2835);
FORCEPROP 1 LASTPIN (-5450 2825) BN 4
J 2
(-5438 2833);
DISPLAY 0.617021 (-5438 2833);
PAINT GREEN (-5438 2833);
FORCEPROP 2 LAST CDS_LIB mstr_standard
J 0
(-5500 2825);
PAINT MONO (-5500 2825);
DISPLAY INVISIBLE (-5500 2825);
FORCEPROP 1 LAST BODY_TYPE PLUMBING
J 2
(-5500 2875);
DISPLAY 1.446809 (-5500 2875);
PAINT GREEN (-5500 2875);
DISPLAY INVISIBLE (-5500 2875);
FORCEPROP 1 LAST HDL_TAP TRUE
J 2
(-5825 2700);
DISPLAY 1.446809 (-5825 2700);
PAINT GREEN (-5825 2700);
DISPLAY INVISIBLE (-5825 2700);
FORCEPROP 1 LAST PATH I6
J 2
(-5498 2825);
DISPLAY 0.872340 (-5498 2825);
PAINT GREEN (-5498 2825);
DISPLAY INVISIBLE (-5498 2825);
FORCEADD TAP..1
(-2575 2425);
FORCEPROP 3 LASTPIN (-2625 2425) SIG_NAME UPI_CPU1_CPU0_P0P0_DN<17>
J 0
(-2615 2435);
DISPLAY 0.659574 (-2615 2435);
PAINT MONO (-2615 2435);
DISPLAY INVISIBLE (-2615 2435);
FORCEPROP 1 LASTPIN (-2625 2425) BN 17
J 0
(-2637 2433);
DISPLAY 0.617021 (-2637 2433);
PAINT GREEN (-2637 2433);
FORCEPROP 2 LAST CDS_LIB mstr_standard
J 0
(-2575 2425);
PAINT MONO (-2575 2425);
DISPLAY INVISIBLE (-2575 2425);
FORCEPROP 1 LAST BODY_TYPE PLUMBING
J 0
(-2575 2475);
DISPLAY 1.446809 (-2575 2475);
PAINT GREEN (-2575 2475);
DISPLAY INVISIBLE (-2575 2475);
FORCEPROP 1 LAST HDL_TAP TRUE
J 0
(-2250 2300);
DISPLAY 1.446809 (-2250 2300);
PAINT GREEN (-2250 2300);
DISPLAY INVISIBLE (-2250 2300);
FORCEPROP 1 LAST PATH I61
J 0
(-2577 2425);
DISPLAY 0.872340 (-2577 2425);
PAINT GREEN (-2577 2425);
DISPLAY INVISIBLE (-2577 2425);
FORCEADD TAP..1
(-2575 2475);
FORCEPROP 3 LASTPIN (-2625 2475) SIG_NAME UPI_CPU1_CPU0_P0P0_DN<18>
J 0
(-2615 2485);
DISPLAY 0.659574 (-2615 2485);
PAINT MONO (-2615 2485);
DISPLAY INVISIBLE (-2615 2485);
FORCEPROP 1 LASTPIN (-2625 2475) BN 18
J 0
(-2637 2483);
DISPLAY 0.617021 (-2637 2483);
PAINT GREEN (-2637 2483);
FORCEPROP 2 LAST CDS_LIB mstr_standard
J 0
(-2575 2475);
PAINT MONO (-2575 2475);
DISPLAY INVISIBLE (-2575 2475);
FORCEPROP 1 LAST BODY_TYPE PLUMBING
J 0
(-2575 2525);
DISPLAY 1.446809 (-2575 2525);
PAINT GREEN (-2575 2525);
DISPLAY INVISIBLE (-2575 2525);
FORCEPROP 1 LAST HDL_TAP TRUE
J 0
(-2250 2350);
DISPLAY 1.446809 (-2250 2350);
PAINT GREEN (-2250 2350);
DISPLAY INVISIBLE (-2250 2350);
FORCEPROP 1 LAST PATH I62
J 0
(-2577 2475);
DISPLAY 0.872340 (-2577 2475);
PAINT GREEN (-2577 2475);
DISPLAY INVISIBLE (-2577 2475);
FORCEADD TAP..1
(-2900 2725);
FORCEPROP 3 LASTPIN (-2950 2725) SIG_NAME UPI_CPU1_CPU0_P0P0_DP<2>
J 0
(-2940 2735);
DISPLAY 0.659574 (-2940 2735);
PAINT MONO (-2940 2735);
DISPLAY INVISIBLE (-2940 2735);
FORCEPROP 1 LASTPIN (-2950 2725) BN 2
J 0
(-2962 2733);
DISPLAY 0.617021 (-2962 2733);
PAINT GREEN (-2962 2733);
FORCEPROP 2 LAST CDS_LIB mstr_standard
J 0
(-2900 2725);
PAINT MONO (-2900 2725);
DISPLAY INVISIBLE (-2900 2725);
FORCEPROP 1 LAST BODY_TYPE PLUMBING
J 0
(-2900 2775);
DISPLAY 1.446809 (-2900 2775);
PAINT GREEN (-2900 2775);
DISPLAY INVISIBLE (-2900 2775);
FORCEPROP 1 LAST HDL_TAP TRUE
J 0
(-2575 2600);
DISPLAY 1.446809 (-2575 2600);
PAINT GREEN (-2575 2600);
DISPLAY INVISIBLE (-2575 2600);
FORCEPROP 1 LAST PATH I66
J 0
(-2902 2725);
DISPLAY 0.872340 (-2902 2725);
PAINT GREEN (-2902 2725);
DISPLAY INVISIBLE (-2902 2725);
FORCEADD TAP..1
(-2900 2775);
FORCEPROP 3 LASTPIN (-2950 2775) SIG_NAME UPI_CPU1_CPU0_P0P0_DP<3>
J 0
(-2940 2785);
DISPLAY 0.659574 (-2940 2785);
PAINT MONO (-2940 2785);
DISPLAY INVISIBLE (-2940 2785);
FORCEPROP 1 LASTPIN (-2950 2775) BN 3
J 0
(-2962 2783);
DISPLAY 0.617021 (-2962 2783);
PAINT GREEN (-2962 2783);
FORCEPROP 2 LAST CDS_LIB mstr_standard
J 0
(-2900 2775);
PAINT MONO (-2900 2775);
DISPLAY INVISIBLE (-2900 2775);
FORCEPROP 1 LAST BODY_TYPE PLUMBING
J 0
(-2900 2825);
DISPLAY 1.446809 (-2900 2825);
PAINT GREEN (-2900 2825);
DISPLAY INVISIBLE (-2900 2825);
FORCEPROP 1 LAST HDL_TAP TRUE
J 0
(-2575 2650);
DISPLAY 1.446809 (-2575 2650);
PAINT GREEN (-2575 2650);
DISPLAY INVISIBLE (-2575 2650);
FORCEPROP 1 LAST PATH I67
J 0
(-2902 2775);
DISPLAY 0.872340 (-2902 2775);
PAINT GREEN (-2902 2775);
DISPLAY INVISIBLE (-2902 2775);
FORCEADD TAP..1
(-2900 1825);
FORCEPROP 3 LASTPIN (-2950 1825) SIG_NAME UPI_CPU1_CPU0_P0P0_DP<5>
J 0
(-2940 1835);
DISPLAY 0.659574 (-2940 1835);
PAINT MONO (-2940 1835);
DISPLAY INVISIBLE (-2940 1835);
FORCEPROP 1 LASTPIN (-2950 1825) BN 5
J 0
(-2962 1833);
DISPLAY 0.617021 (-2962 1833);
PAINT GREEN (-2962 1833);
FORCEPROP 2 LAST CDS_LIB mstr_standard
J 0
(-2900 1825);
PAINT MONO (-2900 1825);
DISPLAY INVISIBLE (-2900 1825);
FORCEPROP 1 LAST BODY_TYPE PLUMBING
J 0
(-2900 1875);
DISPLAY 1.446809 (-2900 1875);
PAINT GREEN (-2900 1875);
DISPLAY INVISIBLE (-2900 1875);
FORCEPROP 1 LAST HDL_TAP TRUE
J 0
(-2575 1700);
DISPLAY 1.446809 (-2575 1700);
PAINT GREEN (-2575 1700);
DISPLAY INVISIBLE (-2575 1700);
FORCEPROP 1 LAST PATH I69
J 0
(-2902 1825);
DISPLAY 0.872340 (-2902 1825);
PAINT GREEN (-2902 1825);
DISPLAY INVISIBLE (-2902 1825);
FORCEADD TAP..1
R 2
(-5500 2775);
FORCEPROP 3 LASTPIN (-5450 2775) SIG_NAME UPI_CPU0_CPU1_P0P0_DN<3>
J 0
(-5440 2785);
DISPLAY 0.659574 (-5440 2785);
PAINT MONO (-5440 2785);
DISPLAY INVISIBLE (-5440 2785);
FORCEPROP 1 LASTPIN (-5450 2775) BN 3
J 2
(-5438 2783);
DISPLAY 0.617021 (-5438 2783);
PAINT GREEN (-5438 2783);
FORCEPROP 2 LAST CDS_LIB mstr_standard
J 0
(-5500 2775);
PAINT MONO (-5500 2775);
DISPLAY INVISIBLE (-5500 2775);
FORCEPROP 1 LAST BODY_TYPE PLUMBING
J 2
(-5500 2825);
DISPLAY 1.446809 (-5500 2825);
PAINT GREEN (-5500 2825);
DISPLAY INVISIBLE (-5500 2825);
FORCEPROP 1 LAST HDL_TAP TRUE
J 2
(-5825 2650);
DISPLAY 1.446809 (-5825 2650);
PAINT GREEN (-5825 2650);
DISPLAY INVISIBLE (-5825 2650);
FORCEPROP 1 LAST PATH I7
J 2
(-5498 2775);
DISPLAY 0.872340 (-5498 2775);
PAINT GREEN (-5498 2775);
DISPLAY INVISIBLE (-5498 2775);
FORCEADD TAP..1
(-2900 2975);
FORCEPROP 3 LASTPIN (-2950 2975) SIG_NAME UPI_CPU1_CPU0_P0P0_DP<7>
J 0
(-2940 2985);
DISPLAY 0.659574 (-2940 2985);
PAINT MONO (-2940 2985);
DISPLAY INVISIBLE (-2940 2985);
FORCEPROP 1 LASTPIN (-2950 2975) BN 7
J 0
(-2962 2983);
DISPLAY 0.617021 (-2962 2983);
PAINT GREEN (-2962 2983);
FORCEPROP 2 LAST CDS_LIB mstr_standard
J 0
(-2900 2975);
PAINT MONO (-2900 2975);
DISPLAY INVISIBLE (-2900 2975);
FORCEPROP 1 LAST BODY_TYPE PLUMBING
J 0
(-2900 3025);
DISPLAY 1.446809 (-2900 3025);
PAINT GREEN (-2900 3025);
DISPLAY INVISIBLE (-2900 3025);
FORCEPROP 1 LAST HDL_TAP TRUE
J 0
(-2575 2850);
DISPLAY 1.446809 (-2575 2850);
PAINT GREEN (-2575 2850);
DISPLAY INVISIBLE (-2575 2850);
FORCEPROP 1 LAST PATH I72
J 0
(-2902 2975);
DISPLAY 0.872340 (-2902 2975);
PAINT GREEN (-2902 2975);
DISPLAY INVISIBLE (-2902 2975);
FORCEADD TAP..1
(-2900 3075);
FORCEPROP 3 LASTPIN (-2950 3075) SIG_NAME UPI_CPU1_CPU0_P0P0_DP<9>
J 0
(-2940 3085);
DISPLAY 0.659574 (-2940 3085);
PAINT MONO (-2940 3085);
DISPLAY INVISIBLE (-2940 3085);
FORCEPROP 1 LASTPIN (-2950 3075) BN 9
J 0
(-2962 3083);
DISPLAY 0.617021 (-2962 3083);
PAINT GREEN (-2962 3083);
FORCEPROP 2 LAST CDS_LIB mstr_standard
J 0
(-2900 3075);
PAINT MONO (-2900 3075);
DISPLAY INVISIBLE (-2900 3075);
FORCEPROP 1 LAST BODY_TYPE PLUMBING
J 0
(-2900 3125);
DISPLAY 1.446809 (-2900 3125);
PAINT GREEN (-2900 3125);
DISPLAY INVISIBLE (-2900 3125);
FORCEPROP 1 LAST HDL_TAP TRUE
J 0
(-2575 2950);
DISPLAY 1.446809 (-2575 2950);
PAINT GREEN (-2575 2950);
DISPLAY INVISIBLE (-2575 2950);
FORCEPROP 1 LAST PATH I73
J 0
(-2902 3075);
DISPLAY 0.872340 (-2902 3075);
PAINT GREEN (-2902 3075);
DISPLAY INVISIBLE (-2902 3075);
FORCEADD TAP..1
(-2900 2075);
FORCEPROP 3 LASTPIN (-2950 2075) SIG_NAME UPI_CPU1_CPU0_P0P0_DP<10>
J 0
(-2940 2085);
DISPLAY 0.659574 (-2940 2085);
PAINT MONO (-2940 2085);
DISPLAY INVISIBLE (-2940 2085);
FORCEPROP 1 LASTPIN (-2950 2075) BN 10
J 0
(-2962 2083);
DISPLAY 0.617021 (-2962 2083);
PAINT GREEN (-2962 2083);
FORCEPROP 2 LAST CDS_LIB mstr_standard
J 0
(-2900 2075);
PAINT MONO (-2900 2075);
DISPLAY INVISIBLE (-2900 2075);
FORCEPROP 1 LAST BODY_TYPE PLUMBING
J 0
(-2900 2125);
DISPLAY 1.446809 (-2900 2125);
PAINT GREEN (-2900 2125);
DISPLAY INVISIBLE (-2900 2125);
FORCEPROP 1 LAST HDL_TAP TRUE
J 0
(-2575 1950);
DISPLAY 1.446809 (-2575 1950);
PAINT GREEN (-2575 1950);
DISPLAY INVISIBLE (-2575 1950);
FORCEPROP 1 LAST PATH I74
J 0
(-2902 2075);
DISPLAY 0.872340 (-2902 2075);
PAINT GREEN (-2902 2075);
DISPLAY INVISIBLE (-2902 2075);
FORCEADD TAP..1
(-2900 2275);
FORCEPROP 3 LASTPIN (-2950 2275) SIG_NAME UPI_CPU1_CPU0_P0P0_DP<14>
J 0
(-2940 2285);
DISPLAY 0.659574 (-2940 2285);
PAINT MONO (-2940 2285);
DISPLAY INVISIBLE (-2940 2285);
FORCEPROP 1 LASTPIN (-2950 2275) BN 14
J 0
(-2962 2283);
DISPLAY 0.617021 (-2962 2283);
PAINT GREEN (-2962 2283);
FORCEPROP 2 LAST CDS_LIB mstr_standard
J 0
(-2900 2275);
PAINT MONO (-2900 2275);
DISPLAY INVISIBLE (-2900 2275);
FORCEPROP 1 LAST BODY_TYPE PLUMBING
J 0
(-2900 2325);
DISPLAY 1.446809 (-2900 2325);
PAINT GREEN (-2900 2325);
DISPLAY INVISIBLE (-2900 2325);
FORCEPROP 1 LAST HDL_TAP TRUE
J 0
(-2575 2150);
DISPLAY 1.446809 (-2575 2150);
PAINT GREEN (-2575 2150);
DISPLAY INVISIBLE (-2575 2150);
FORCEPROP 1 LAST PATH I78
J 0
(-2902 2275);
DISPLAY 0.872340 (-2902 2275);
PAINT GREEN (-2902 2275);
DISPLAY INVISIBLE (-2902 2275);
FORCEADD TAP..1
(-2900 3475);
FORCEPROP 3 LASTPIN (-2950 3475) SIG_NAME UPI_CPU1_CPU0_P0P0_DP<17>
J 0
(-2940 3485);
DISPLAY 0.659574 (-2940 3485);
PAINT MONO (-2940 3485);
DISPLAY INVISIBLE (-2940 3485);
FORCEPROP 1 LASTPIN (-2950 3475) BN 17
J 0
(-2962 3483);
DISPLAY 0.617021 (-2962 3483);
PAINT GREEN (-2962 3483);
FORCEPROP 2 LAST CDS_LIB mstr_standard
J 0
(-2900 3475);
PAINT MONO (-2900 3475);
DISPLAY INVISIBLE (-2900 3475);
FORCEPROP 1 LAST BODY_TYPE PLUMBING
J 0
(-2900 3525);
DISPLAY 1.446809 (-2900 3525);
PAINT GREEN (-2900 3525);
DISPLAY INVISIBLE (-2900 3525);
FORCEPROP 1 LAST HDL_TAP TRUE
J 0
(-2575 3350);
DISPLAY 1.446809 (-2575 3350);
PAINT GREEN (-2575 3350);
DISPLAY INVISIBLE (-2575 3350);
FORCEPROP 1 LAST PATH I81
J 0
(-2902 3475);
DISPLAY 0.872340 (-2902 3475);
PAINT GREEN (-2902 3475);
DISPLAY INVISIBLE (-2902 3475);
FORCEADD TAP..1
(-2900 3525);
FORCEPROP 3 LASTPIN (-2950 3525) SIG_NAME UPI_CPU1_CPU0_P0P0_DP<18>
J 0
(-2940 3535);
DISPLAY 0.659574 (-2940 3535);
PAINT MONO (-2940 3535);
DISPLAY INVISIBLE (-2940 3535);
FORCEPROP 1 LASTPIN (-2950 3525) BN 18
J 0
(-2962 3533);
DISPLAY 0.617021 (-2962 3533);
PAINT GREEN (-2962 3533);
FORCEPROP 2 LAST CDS_LIB mstr_standard
J 0
(-2900 3525);
PAINT MONO (-2900 3525);
DISPLAY INVISIBLE (-2900 3525);
FORCEPROP 1 LAST BODY_TYPE PLUMBING
J 0
(-2900 3575);
DISPLAY 1.446809 (-2900 3575);
PAINT GREEN (-2900 3575);
DISPLAY INVISIBLE (-2900 3575);
FORCEPROP 1 LAST HDL_TAP TRUE
J 0
(-2575 3400);
DISPLAY 1.446809 (-2575 3400);
PAINT GREEN (-2575 3400);
DISPLAY INVISIBLE (-2575 3400);
FORCEPROP 1 LAST PATH I83
J 0
(-2902 3525);
DISPLAY 0.872340 (-2902 3525);
PAINT GREEN (-2902 3525);
DISPLAY INVISIBLE (-2902 3525);
FORCEADD OFFPAGE..2
(-1550 3650);
FORCEPROP 2 LAST $XR0 33 
J 0
(-1361 3650);
DISPLAY 0.638298 (-1361 3650);
PAINT MONO (-1361 3650);
FORCEPROP 2 LAST CDS_LIB mstr_standard
J 0
(-1550 3650);
PAINT MONO (-1550 3650);
DISPLAY INVISIBLE (-1550 3650);
FORCEPROP 1 LAST OFFPAGE TRUE
J 0
(-1225 3525);
DISPLAY 1.170213 (-1225 3525);
PAINT GREEN (-1225 3525);
DISPLAY INVISIBLE (-1225 3525);
FORCEPROP 1 LAST COMMENT_BODY TRUE
J 0
(-1595 3555);
DISPLAY 1.170213 (-1595 3555);
PAINT GREEN (-1595 3555);
DISPLAY INVISIBLE (-1595 3555);
FORCEPROP 2 LAST PATH I84
J 0
(-1375 3725);
DISPLAY 1.021277 (-1375 3725);
PAINT ORANGE (-1375 3725);
DISPLAY INVISIBLE (-1375 3725);
FORCEADD OFFPAGE..2
(-1550 3725);
FORCEPROP 2 LAST $XR0 33 
J 0
(-1361 3725);
DISPLAY 0.638298 (-1361 3725);
PAINT MONO (-1361 3725);
FORCEPROP 2 LAST CDS_LIB mstr_standard
J 0
(-1550 3725);
PAINT MONO (-1550 3725);
DISPLAY INVISIBLE (-1550 3725);
FORCEPROP 1 LAST OFFPAGE TRUE
J 0
(-1225 3600);
DISPLAY 1.170213 (-1225 3600);
PAINT GREEN (-1225 3600);
DISPLAY INVISIBLE (-1225 3600);
FORCEPROP 1 LAST COMMENT_BODY TRUE
J 0
(-1595 3630);
DISPLAY 1.170213 (-1595 3630);
PAINT GREEN (-1595 3630);
DISPLAY INVISIBLE (-1595 3630);
FORCEPROP 2 LAST PATH I85
J 0
(-1375 3800);
DISPLAY 1.021277 (-1375 3800);
PAINT ORANGE (-1375 3800);
DISPLAY INVISIBLE (-1375 3800);
FORCEADD TAP..1
R 2
(-5500 3525);
FORCEPROP 3 LASTPIN (-5450 3525) SIG_NAME UPI_CPU0_CPU1_P0P0_DN<18>
J 0
(-5440 3535);
DISPLAY 0.659574 (-5440 3535);
PAINT MONO (-5440 3535);
DISPLAY INVISIBLE (-5440 3535);
FORCEPROP 1 LASTPIN (-5450 3525) BN 18
J 2
(-5438 3533);
DISPLAY 0.617021 (-5438 3533);
PAINT GREEN (-5438 3533);
FORCEPROP 2 LAST CDS_LIB mstr_standard
J 0
(-5500 3525);
PAINT MONO (-5500 3525);
DISPLAY INVISIBLE (-5500 3525);
FORCEPROP 1 LAST BODY_TYPE PLUMBING
J 2
(-5500 3575);
DISPLAY 1.446809 (-5500 3575);
PAINT GREEN (-5500 3575);
DISPLAY INVISIBLE (-5500 3575);
FORCEPROP 1 LAST HDL_TAP TRUE
J 2
(-5825 3400);
DISPLAY 1.446809 (-5825 3400);
PAINT GREEN (-5825 3400);
DISPLAY INVISIBLE (-5825 3400);
FORCEPROP 1 LAST PATH I86
J 2
(-5498 3525);
DISPLAY 0.872340 (-5498 3525);
PAINT GREEN (-5498 3525);
DISPLAY INVISIBLE (-5498 3525);
FORCEADD TAP..1
R 2
(-5500 3575);
FORCEPROP 3 LASTPIN (-5450 3575) SIG_NAME UPI_CPU0_CPU1_P0P0_DN<19>
J 0
(-5440 3585);
DISPLAY 0.659574 (-5440 3585);
PAINT MONO (-5440 3585);
DISPLAY INVISIBLE (-5440 3585);
FORCEPROP 1 LASTPIN (-5450 3575) BN 19
J 2
(-5438 3583);
DISPLAY 0.617021 (-5438 3583);
PAINT GREEN (-5438 3583);
FORCEPROP 2 LAST CDS_LIB mstr_standard
J 0
(-5500 3575);
PAINT MONO (-5500 3575);
DISPLAY INVISIBLE (-5500 3575);
FORCEPROP 1 LAST BODY_TYPE PLUMBING
J 2
(-5500 3625);
DISPLAY 1.446809 (-5500 3625);
PAINT GREEN (-5500 3625);
DISPLAY INVISIBLE (-5500 3625);
FORCEPROP 1 LAST HDL_TAP TRUE
J 2
(-5825 3450);
DISPLAY 1.446809 (-5825 3450);
PAINT GREEN (-5825 3450);
DISPLAY INVISIBLE (-5825 3450);
FORCEPROP 1 LAST PATH I87
J 2
(-5498 3575);
DISPLAY 0.872340 (-5498 3575);
PAINT GREEN (-5498 3575);
DISPLAY INVISIBLE (-5498 3575);
FORCEADD TAP..1
R 2
(-5500 2625);
FORCEPROP 3 LASTPIN (-5450 2625) SIG_NAME UPI_CPU0_CPU1_P0P0_DN<0>
J 0
(-5440 2635);
DISPLAY 0.659574 (-5440 2635);
PAINT MONO (-5440 2635);
DISPLAY INVISIBLE (-5440 2635);
FORCEPROP 1 LASTPIN (-5450 2625) BN 0
J 2
(-5438 2633);
DISPLAY 0.617021 (-5438 2633);
PAINT GREEN (-5438 2633);
FORCEPROP 2 LAST CDS_LIB mstr_standard
J 0
(-5500 2625);
PAINT MONO (-5500 2625);
DISPLAY INVISIBLE (-5500 2625);
FORCEPROP 1 LAST BODY_TYPE PLUMBING
J 2
(-5500 2675);
DISPLAY 1.446809 (-5500 2675);
PAINT GREEN (-5500 2675);
DISPLAY INVISIBLE (-5500 2675);
FORCEPROP 1 LAST HDL_TAP TRUE
J 2
(-5825 2500);
DISPLAY 1.446809 (-5825 2500);
PAINT GREEN (-5825 2500);
DISPLAY INVISIBLE (-5825 2500);
FORCEPROP 1 LAST PATH I88
J 2
(-5498 2625);
DISPLAY 0.872340 (-5498 2625);
PAINT GREEN (-5498 2625);
DISPLAY INVISIBLE (-5498 2625);
FORCEADD TAP..1
R 2
(-5500 2875);
FORCEPROP 3 LASTPIN (-5450 2875) SIG_NAME UPI_CPU0_CPU1_P0P0_DN<5>
J 0
(-5440 2885);
DISPLAY 0.659574 (-5440 2885);
PAINT MONO (-5440 2885);
DISPLAY INVISIBLE (-5440 2885);
FORCEPROP 1 LASTPIN (-5450 2875) BN 5
J 2
(-5438 2883);
DISPLAY 0.617021 (-5438 2883);
PAINT GREEN (-5438 2883);
FORCEPROP 2 LAST CDS_LIB mstr_standard
J 0
(-5500 2875);
PAINT MONO (-5500 2875);
DISPLAY INVISIBLE (-5500 2875);
FORCEPROP 1 LAST BODY_TYPE PLUMBING
J 2
(-5500 2925);
DISPLAY 1.446809 (-5500 2925);
PAINT GREEN (-5500 2925);
DISPLAY INVISIBLE (-5500 2925);
FORCEPROP 1 LAST HDL_TAP TRUE
J 2
(-5825 2750);
DISPLAY 1.446809 (-5825 2750);
PAINT GREEN (-5825 2750);
DISPLAY INVISIBLE (-5825 2750);
FORCEPROP 1 LAST PATH I89
J 2
(-5498 2875);
DISPLAY 0.872340 (-5498 2875);
PAINT GREEN (-5498 2875);
DISPLAY INVISIBLE (-5498 2875);
FORCEADD TAP..1
R 2
(-5500 2925);
FORCEPROP 3 LASTPIN (-5450 2925) SIG_NAME UPI_CPU0_CPU1_P0P0_DN<6>
J 0
(-5440 2935);
DISPLAY 0.659574 (-5440 2935);
PAINT MONO (-5440 2935);
DISPLAY INVISIBLE (-5440 2935);
FORCEPROP 1 LASTPIN (-5450 2925) BN 6
J 2
(-5438 2933);
DISPLAY 0.617021 (-5438 2933);
PAINT GREEN (-5438 2933);
FORCEPROP 2 LAST CDS_LIB mstr_standard
J 0
(-5500 2925);
PAINT MONO (-5500 2925);
DISPLAY INVISIBLE (-5500 2925);
FORCEPROP 1 LAST BODY_TYPE PLUMBING
J 2
(-5500 2975);
DISPLAY 1.446809 (-5500 2975);
PAINT GREEN (-5500 2975);
DISPLAY INVISIBLE (-5500 2975);
FORCEPROP 1 LAST HDL_TAP TRUE
J 2
(-5825 2800);
DISPLAY 1.446809 (-5825 2800);
PAINT GREEN (-5825 2800);
DISPLAY INVISIBLE (-5825 2800);
FORCEPROP 1 LAST PATH I90
J 2
(-5498 2925);
DISPLAY 0.872340 (-5498 2925);
PAINT GREEN (-5498 2925);
DISPLAY INVISIBLE (-5498 2925);
FORCEADD TAP..1
R 2
(-5500 2975);
FORCEPROP 3 LASTPIN (-5450 2975) SIG_NAME UPI_CPU0_CPU1_P0P0_DN<7>
J 0
(-5440 2985);
DISPLAY 0.659574 (-5440 2985);
PAINT MONO (-5440 2985);
DISPLAY INVISIBLE (-5440 2985);
FORCEPROP 1 LASTPIN (-5450 2975) BN 7
J 2
(-5438 2983);
DISPLAY 0.617021 (-5438 2983);
PAINT GREEN (-5438 2983);
FORCEPROP 2 LAST CDS_LIB mstr_standard
J 0
(-5500 2975);
PAINT MONO (-5500 2975);
DISPLAY INVISIBLE (-5500 2975);
FORCEPROP 1 LAST BODY_TYPE PLUMBING
J 2
(-5500 3025);
DISPLAY 1.446809 (-5500 3025);
PAINT GREEN (-5500 3025);
DISPLAY INVISIBLE (-5500 3025);
FORCEPROP 1 LAST HDL_TAP TRUE
J 2
(-5825 2850);
DISPLAY 1.446809 (-5825 2850);
PAINT GREEN (-5825 2850);
DISPLAY INVISIBLE (-5825 2850);
FORCEPROP 1 LAST PATH I91
J 2
(-5498 2975);
DISPLAY 0.872340 (-5498 2975);
PAINT GREEN (-5498 2975);
DISPLAY INVISIBLE (-5498 2975);
FORCEADD TAP..1
R 2
(-5500 3025);
FORCEPROP 3 LASTPIN (-5450 3025) SIG_NAME UPI_CPU0_CPU1_P0P0_DN<8>
J 0
(-5440 3035);
DISPLAY 0.659574 (-5440 3035);
PAINT MONO (-5440 3035);
DISPLAY INVISIBLE (-5440 3035);
FORCEPROP 1 LASTPIN (-5450 3025) BN 8
J 2
(-5438 3033);
DISPLAY 0.617021 (-5438 3033);
PAINT GREEN (-5438 3033);
FORCEPROP 2 LAST CDS_LIB mstr_standard
J 0
(-5500 3025);
PAINT MONO (-5500 3025);
DISPLAY INVISIBLE (-5500 3025);
FORCEPROP 1 LAST BODY_TYPE PLUMBING
J 2
(-5500 3075);
DISPLAY 1.446809 (-5500 3075);
PAINT GREEN (-5500 3075);
DISPLAY INVISIBLE (-5500 3075);
FORCEPROP 1 LAST HDL_TAP TRUE
J 2
(-5825 2900);
DISPLAY 1.446809 (-5825 2900);
PAINT GREEN (-5825 2900);
DISPLAY INVISIBLE (-5825 2900);
FORCEPROP 1 LAST PATH I92
J 2
(-5498 3025);
DISPLAY 0.872340 (-5498 3025);
PAINT GREEN (-5498 3025);
DISPLAY INVISIBLE (-5498 3025);
FORCEADD TAP..1
R 2
(-5500 3075);
FORCEPROP 3 LASTPIN (-5450 3075) SIG_NAME UPI_CPU0_CPU1_P0P0_DN<9>
J 0
(-5440 3085);
DISPLAY 0.659574 (-5440 3085);
PAINT MONO (-5440 3085);
DISPLAY INVISIBLE (-5440 3085);
FORCEPROP 1 LASTPIN (-5450 3075) BN 9
J 2
(-5438 3083);
DISPLAY 0.617021 (-5438 3083);
PAINT GREEN (-5438 3083);
FORCEPROP 2 LAST CDS_LIB mstr_standard
J 0
(-5500 3075);
PAINT MONO (-5500 3075);
DISPLAY INVISIBLE (-5500 3075);
FORCEPROP 1 LAST BODY_TYPE PLUMBING
J 2
(-5500 3125);
DISPLAY 1.446809 (-5500 3125);
PAINT GREEN (-5500 3125);
DISPLAY INVISIBLE (-5500 3125);
FORCEPROP 1 LAST HDL_TAP TRUE
J 2
(-5825 2950);
DISPLAY 1.446809 (-5825 2950);
PAINT GREEN (-5825 2950);
DISPLAY INVISIBLE (-5825 2950);
FORCEPROP 1 LAST PATH I93
J 2
(-5498 3075);
DISPLAY 0.872340 (-5498 3075);
PAINT GREEN (-5498 3075);
DISPLAY INVISIBLE (-5498 3075);
FORCEADD TAP..1
R 2
(-5500 2225);
FORCEPROP 3 LASTPIN (-5450 2225) SIG_NAME UPI_CPU0_CPU1_P0P0_DN<13>
J 0
(-5440 2235);
DISPLAY 0.659574 (-5440 2235);
PAINT MONO (-5440 2235);
DISPLAY INVISIBLE (-5440 2235);
FORCEPROP 1 LASTPIN (-5450 2225) BN 13
J 2
(-5438 2233);
DISPLAY 0.617021 (-5438 2233);
PAINT GREEN (-5438 2233);
FORCEPROP 2 LAST CDS_LIB mstr_standard
J 0
(-5500 2225);
PAINT ORANGE (-5500 2225);
DISPLAY INVISIBLE (-5500 2225);
FORCEPROP 1 LAST BODY_TYPE PLUMBING
J 2
(-5500 2275);
DISPLAY 1.446809 (-5500 2275);
PAINT GREEN (-5500 2275);
DISPLAY INVISIBLE (-5500 2275);
FORCEPROP 1 LAST HDL_TAP TRUE
J 2
(-5825 2100);
DISPLAY 1.446809 (-5825 2100);
PAINT GREEN (-5825 2100);
DISPLAY INVISIBLE (-5825 2100);
FORCEPROP 1 LAST PATH I94
J 2
(-5498 2225);
DISPLAY 0.872340 (-5498 2225);
PAINT GREEN (-5498 2225);
DISPLAY INVISIBLE (-5498 2225);
FORCEADD TAP..1
R 2
(-5500 3325);
FORCEPROP 3 LASTPIN (-5450 3325) SIG_NAME UPI_CPU0_CPU1_P0P0_DN<14>
J 0
(-5440 3335);
DISPLAY 0.659574 (-5440 3335);
PAINT MONO (-5440 3335);
DISPLAY INVISIBLE (-5440 3335);
FORCEPROP 1 LASTPIN (-5450 3325) BN 14
J 2
(-5438 3333);
DISPLAY 0.617021 (-5438 3333);
PAINT GREEN (-5438 3333);
FORCEPROP 2 LAST CDS_LIB mstr_standard
J 0
(-5500 3325);
PAINT MONO (-5500 3325);
DISPLAY INVISIBLE (-5500 3325);
FORCEPROP 1 LAST BODY_TYPE PLUMBING
J 2
(-5500 3375);
DISPLAY 1.446809 (-5500 3375);
PAINT GREEN (-5500 3375);
DISPLAY INVISIBLE (-5500 3375);
FORCEPROP 1 LAST HDL_TAP TRUE
J 2
(-5825 3200);
DISPLAY 1.446809 (-5825 3200);
PAINT GREEN (-5825 3200);
DISPLAY INVISIBLE (-5825 3200);
FORCEPROP 1 LAST PATH I95
J 2
(-5498 3325);
DISPLAY 0.872340 (-5498 3325);
PAINT GREEN (-5498 3325);
DISPLAY INVISIBLE (-5498 3325);
FORCEADD TAP..1
R 2
(-5500 2325);
FORCEPROP 3 LASTPIN (-5450 2325) SIG_NAME UPI_CPU0_CPU1_P0P0_DN<15>
J 0
(-5440 2335);
DISPLAY 0.659574 (-5440 2335);
PAINT MONO (-5440 2335);
DISPLAY INVISIBLE (-5440 2335);
FORCEPROP 1 LASTPIN (-5450 2325) BN 15
J 2
(-5438 2333);
DISPLAY 0.617021 (-5438 2333);
PAINT GREEN (-5438 2333);
FORCEPROP 2 LAST CDS_LIB mstr_standard
J 0
(-5500 2325);
PAINT MONO (-5500 2325);
DISPLAY INVISIBLE (-5500 2325);
FORCEPROP 1 LAST BODY_TYPE PLUMBING
J 2
(-5500 2375);
DISPLAY 1.446809 (-5500 2375);
PAINT GREEN (-5500 2375);
DISPLAY INVISIBLE (-5500 2375);
FORCEPROP 1 LAST HDL_TAP TRUE
J 2
(-5825 2200);
DISPLAY 1.446809 (-5825 2200);
PAINT GREEN (-5825 2200);
DISPLAY INVISIBLE (-5825 2200);
FORCEPROP 1 LAST PATH I96
J 2
(-5498 2325);
DISPLAY 0.872340 (-5498 2325);
PAINT GREEN (-5498 2325);
DISPLAY INVISIBLE (-5498 2325);
FORCEADD TAP..1
R 2
(-5500 3175);
FORCEPROP 3 LASTPIN (-5450 3175) SIG_NAME UPI_CPU0_CPU1_P0P0_DN<11>
J 0
(-5440 3185);
DISPLAY 0.659574 (-5440 3185);
PAINT MONO (-5440 3185);
DISPLAY INVISIBLE (-5440 3185);
FORCEPROP 1 LASTPIN (-5450 3175) BN 11
J 2
(-5438 3183);
DISPLAY 0.617021 (-5438 3183);
PAINT GREEN (-5438 3183);
FORCEPROP 2 LAST CDS_LIB mstr_standard
J 0
(-5500 3175);
PAINT MONO (-5500 3175);
DISPLAY INVISIBLE (-5500 3175);
FORCEPROP 1 LAST BODY_TYPE PLUMBING
J 2
(-5500 3225);
DISPLAY 1.446809 (-5500 3225);
PAINT GREEN (-5500 3225);
DISPLAY INVISIBLE (-5500 3225);
FORCEPROP 1 LAST HDL_TAP TRUE
J 2
(-5825 3050);
DISPLAY 1.446809 (-5825 3050);
PAINT GREEN (-5825 3050);
DISPLAY INVISIBLE (-5825 3050);
FORCEPROP 1 LAST PATH I97
J 2
(-5498 3175);
DISPLAY 0.872340 (-5498 3175);
PAINT GREEN (-5498 3175);
DISPLAY INVISIBLE (-5498 3175);
FORCEADD TAP..1
R 2
(-5225 3375);
FORCEPROP 3 LASTPIN (-5175 3375) SIG_NAME UPI_CPU0_CPU1_P0P0_DP<15>
J 0
(-5165 3385);
DISPLAY 0.659574 (-5165 3385);
PAINT MONO (-5165 3385);
DISPLAY INVISIBLE (-5165 3385);
FORCEPROP 1 LASTPIN (-5175 3375) BN 15
J 2
(-5163 3383);
DISPLAY 0.617021 (-5163 3383);
PAINT GREEN (-5163 3383);
FORCEPROP 2 LAST CDS_LIB mstr_standard
J 0
(-5225 3375);
PAINT MONO (-5225 3375);
DISPLAY INVISIBLE (-5225 3375);
FORCEPROP 1 LAST BODY_TYPE PLUMBING
J 2
(-5225 3425);
DISPLAY 1.446809 (-5225 3425);
PAINT GREEN (-5225 3425);
DISPLAY INVISIBLE (-5225 3425);
FORCEPROP 1 LAST HDL_TAP TRUE
J 2
(-5550 3250);
DISPLAY 1.446809 (-5550 3250);
PAINT GREEN (-5550 3250);
DISPLAY INVISIBLE (-5550 3250);
FORCEPROP 1 LAST PATH I98
J 2
(-5223 3375);
DISPLAY 0.872340 (-5223 3375);
PAINT GREEN (-5223 3375);
DISPLAY INVISIBLE (-5223 3375);
FORCEADD TAP..1
R 2
(-5225 2275);
FORCEPROP 3 LASTPIN (-5175 2275) SIG_NAME UPI_CPU0_CPU1_P0P0_DP<14>
J 0
(-5165 2285);
DISPLAY 0.659574 (-5165 2285);
PAINT MONO (-5165 2285);
DISPLAY INVISIBLE (-5165 2285);
FORCEPROP 1 LASTPIN (-5175 2275) BN 14
J 2
(-5163 2283);
DISPLAY 0.617021 (-5163 2283);
PAINT GREEN (-5163 2283);
FORCEPROP 2 LAST CDS_LIB mstr_standard
J 0
(-5225 2275);
PAINT MONO (-5225 2275);
DISPLAY INVISIBLE (-5225 2275);
FORCEPROP 1 LAST BODY_TYPE PLUMBING
J 2
(-5225 2325);
DISPLAY 1.446809 (-5225 2325);
PAINT GREEN (-5225 2325);
DISPLAY INVISIBLE (-5225 2325);
FORCEPROP 1 LAST HDL_TAP TRUE
J 2
(-5550 2150);
DISPLAY 1.446809 (-5550 2150);
PAINT GREEN (-5550 2150);
DISPLAY INVISIBLE (-5550 2150);
FORCEPROP 1 LAST PATH I99
J 2
(-5223 2275);
DISPLAY 0.872340 (-5223 2275);
PAINT GREEN (-5223 2275);
DISPLAY INVISIBLE (-5223 2275);
FORCEADD PRELIM..10
(-4040 2565);
PAINT GRAY (-4040 2565);
FORCEPROP 2 LAST CDS_LIB mstr_misc
J 0
(-4040 2565);
PAINT ORANGE (-4040 2565);
DISPLAY INVISIBLE (-4040 2565);
FORCEPROP 1 LAST COMMENT_BODY TRUE
J 0
(-4040 2565);
PAINT ORANGE (-4040 2565);
DISPLAY INVISIBLE (-4040 2565);
FORCEADD INTEL_CORP_BPAGE..1
(0 0);
FORCEPROP 1 LAST CDS_CON_LAST_MODIFIED Fri Jun 16 17:48:25 2017
J 0
(-1425 325);
DISPLAY 1.340426 (-1425 325);
PAINT GREEN (-1425 325);
DISPLAY INVISIBLE (-1425 325);
FORCEPROP 1 LAST CUSTOM_TXT_CDS <CURRENT_DESIGN_SHEET> OF <TOTAL_DESIGN_SHEETS>
J 0
(-500 25);
PAINT ORANGE (-500 25);
FORCEPROP 1 LAST CUSTOM_TXT_CDS <CON_LAST_MODIFIED>
J 0
(-4000 100);
PAINT ORANGE (-4000 100);
FORCEPROP 2 LAST CUSTOM_TXT_CDS <XR_PAGE_TITLE>
J 0
(-7890 5250);
DISPLAY 0.638298 (-7890 5250);
PAINT PINK (-7890 5250);
DISPLAY INVISIBLE (-7890 5250);
FORCEPROP 1 LAST SCH_TITLE SKYLAKE - SKT1 - 13 OF 21
J 0
(-7950 50);
DISPLAY 1.212766 (-7950 50);
PAINT GREEN (-7950 50);
FORCEPROP 2 LAST PAGE_BORDER TRUE
J 0
(-7890 5250);
DISPLAY 0.851064 (-7890 5250);
PAINT PINK (-7890 5250);
DISPLAY INVISIBLE (-7890 5250);
FORCEPROP 2 LAST CDS_LIB mstr_symbols
J 0
(0 0);
PAINT ORANGE (0 0);
DISPLAY INVISIBLE (0 0);
FORCEPROP 1 LAST COMMENT_BODY TRUE
J 0
(12 12);
DISPLAY 0.638298 (12 12);
PAINT GREEN (12 12);
DISPLAY INVISIBLE (12 12);
FORCEPROP 2 LAST CDS_XR_PAGE_TITLE CR-67 : @BASEBOARD_FAB2_LIB.BASEBOARD_FAB2(SCH_1):PAGE67
J 0
(-7890 5250);
DISPLAY 0.638298 (-7890 5250);
PAINT PINK (-7890 5250);
DISPLAY INVISIBLE (-7890 5250);
FORCEADD DESIGN_NOTE..1
(-4575 1275);
FORCEPROP 0 LAST L1 CPU SYMBOLS 1-30 ARE PRELIMINARY AND SUBJECT TO CHANGE
J 0
(-4775 1150);
DISPLAY 1.021277 (-4775 1150);
PAINT ORANGE (-4775 1150);
FORCEPROP 2 LAST CDS_LIB mstr_symbols
J 0
(-4575 1275);
PAINT ORANGE (-4575 1275);
DISPLAY INVISIBLE (-4575 1275);
FORCEPROP 1 LAST COMMENT_BODY TRUE
J 0
(-4550 1375);
DISPLAY 0.978723 (-4550 1375);
PAINT ORANGE (-4550 1375);
DISPLAY INVISIBLE (-4550 1375);
WIRE 17 -1 (-2850 1650)(-2850 1600);
WIRE 17 -1 (-2850 1850)(-2850 1650);
WIRE 17 -1 (-2850 3725)(-1600 3725);
FORCEPROP 2 LAST SIG_NAME UPI_CPU1_CPU0_P0P0_DP<19..0>
J 0
(-2285 3735);
DISPLAY 0.617021 (-2285 3735);
PAINT ORANGE (-2285 3735);
WIRE 17 -1 (-2850 2000)(-2850 1850);
WIRE 17 -1 (-2850 2100)(-2850 2000);
WIRE 17 -1 (-2850 3550)(-2850 3725);
WIRE 17 -1 (-2850 3550)(-2850 3500);
WIRE 17 -1 (-2850 2100)(-2850 2150);
WIRE 17 -1 (-2850 2150)(-2850 2200);
WIRE 17 -1 (-2850 3500)(-2850 3100);
WIRE 17 -1 (-2850 3000)(-2850 3100);
WIRE 17 -1 (-2850 2200)(-2850 2250);
WIRE 17 -1 (-2850 2250)(-2850 2300);
WIRE 17 -1 (-2850 2950)(-2850 3000);
WIRE 17 -1 (-2850 2850)(-2850 2950);
WIRE 17 -1 (-2850 2300)(-2850 2350);
WIRE 17 -1 (-2850 2350)(-2850 2400);
WIRE 17 -1 (-2850 2800)(-2850 2850);
WIRE 17 -1 (-2850 2750)(-2850 2800);
WIRE 17 -1 (-2850 2400)(-2850 2550);
WIRE 17 -1 (-2850 2550)(-2850 2750);
WIRE 17 -1 (-2525 3650)(-1600 3650);
FORCEPROP 2 LAST SIG_NAME UPI_CPU1_CPU0_P0P0_DN<19..0>
J 0
(-2285 3660);
DISPLAY 0.617021 (-2285 3660);
PAINT ORANGE (-2285 3660);
WIRE 17 -1 (-2525 3650)(-2525 3600);
WIRE 17 -1 (-2525 3600)(-2525 3450);
WIRE 17 -1 (-2525 3450)(-2525 3400);
WIRE 17 -1 (-2525 3400)(-2525 3350);
WIRE 17 -1 (-2525 3300)(-2525 3350);
WIRE 17 -1 (-2525 1750)(-2525 1700);
WIRE 17 -1 (-2525 3250)(-2525 3300);
WIRE 17 -1 (-2525 3250)(-2525 3200);
WIRE 17 -1 (-2525 1750)(-2525 1800);
WIRE 17 -1 (-2525 1800)(-2525 1900);
WIRE 17 -1 (-2525 3150)(-2525 3200);
WIRE 17 -1 (-2525 3150)(-2525 3050);
WIRE 17 -1 (-2525 1900)(-2525 1950);
WIRE 17 -1 (-2525 1950)(-2525 2050);
WIRE 17 -1 (-2525 3050)(-2525 2900);
WIRE 17 -1 (-2525 2700)(-2525 2900);
WIRE 17 -1 (-2525 2450)(-2525 2050);
WIRE 17 -1 (-2525 2500)(-2525 2450);
WIRE 17 -1 (-2525 2650)(-2525 2700);
WIRE 17 -1 (-2525 2650)(-2525 2500);
WIRE 17 -1 (-5275 1750)(-5275 1600);
WIRE 17 -1 (-5275 1800)(-5275 1750);
WIRE 17 -1 (-6650 3700)(-5275 3700);
FORCEPROP 2 LAST SIG_NAME UPI_CPU0_CPU1_P0P0_DP<19..0>
J 0
(-6600 3710);
DISPLAY 0.617021 (-6600 3710);
PAINT ORANGE (-6600 3710);
WIRE 17 -1 (-5275 1850)(-5275 1800);
WIRE 17 -1 (-5275 1900)(-5275 1850);
WIRE 17 -1 (-5275 3700)(-5275 3500);
WIRE 17 -1 (-5275 3500)(-5275 3450);
WIRE 17 -1 (-5275 1950)(-5275 1900);
WIRE 17 -1 (-5275 2000)(-5275 1950);
WIRE 17 -1 (-5275 3450)(-5275 3400);
WIRE 17 -1 (-5275 3400)(-5275 3300);
WIRE 17 -1 (-5275 2050)(-5275 2000);
WIRE 17 -1 (-5275 2050)(-5275 2150);
WIRE 17 -1 (-5275 3300)(-5275 3250);
WIRE 17 -1 (-5275 3150)(-5275 3250);
WIRE 17 -1 (-5275 2150)(-5275 2300);
WIRE 17 -1 (-5275 2300)(-5275 2500);
WIRE 17 -1 (-5275 2750)(-5275 3150);
WIRE 17 -1 (-5275 2700)(-5275 2750);
WIRE 17 -1 (-5275 2500)(-5275 2550);
WIRE 17 -1 (-5275 2550)(-5275 2700);
WIRE 17 -1 (-6650 3625)(-5550 3625);
FORCEPROP 2 LAST SIG_NAME UPI_CPU0_CPU1_P0P0_DN<19..0>
J 0
(-6600 3635);
DISPLAY 0.617021 (-6600 3635);
PAINT ORANGE (-6600 3635);
WIRE 17 -1 (-5550 3600)(-5550 3625);
WIRE 17 -1 (-5550 3550)(-5550 3600);
WIRE 17 -1 (-5550 3350)(-5550 3550);
WIRE 17 -1 (-5550 3200)(-5550 3350);
WIRE 17 -1 (-5550 3100)(-5550 3200);
WIRE 17 -1 (-5550 3050)(-5550 3100);
WIRE 17 -1 (-5550 1650)(-5550 1700);
WIRE 17 -1 (-5550 1700)(-5550 2100);
WIRE 17 -1 (-5550 3000)(-5550 3050);
WIRE 17 -1 (-5550 2950)(-5550 3000);
WIRE 17 -1 (-5550 2100)(-5550 2200);
WIRE 17 -1 (-5550 2200)(-5550 2250);
WIRE 17 -1 (-5550 2900)(-5550 2950);
WIRE 17 -1 (-5550 2850)(-5550 2900);
WIRE 17 -1 (-5550 2250)(-5550 2350);
WIRE 17 -1 (-5550 2350)(-5550 2400);
WIRE 17 -1 (-5550 2800)(-5550 2850);
WIRE 17 -1 (-5550 2650)(-5550 2800);
WIRE 17 -1 (-5550 2400)(-5550 2450);
WIRE 17 -1 (-5550 2450)(-5550 2650);
WIRE 16 -1 (-2625 3225)(-3250 3225);
WIRE 16 -1 (-5450 3575)(-4850 3575);
WIRE 16 -1 (-5450 2925)(-4850 2925);
WIRE 16 -1 (-5450 3025)(-4850 3025);
WIRE 16 -1 (-5450 2975)(-4850 2975);
WIRE 16 -1 (-5175 1575)(-4850 1575);
WIRE 16 -1 (-5450 1625)(-4850 1625);
WIRE 16 -1 (-5450 1675)(-4850 1675);
WIRE 16 -1 (-5175 1725)(-4850 1725);
WIRE 16 -1 (-5175 1775)(-4850 1775);
WIRE 16 -1 (-5175 1825)(-4850 1825);
WIRE 16 -1 (-5175 1875)(-4850 1875);
WIRE 16 -1 (-5175 1925)(-4850 1925);
WIRE 16 -1 (-5175 1975)(-4850 1975);
WIRE 16 -1 (-5175 2025)(-4850 2025);
WIRE 16 -1 (-5450 2625)(-4850 2625);
WIRE 16 -1 (-5175 2675)(-4850 2675);
WIRE 16 -1 (-5175 2725)(-4850 2725);
WIRE 16 -1 (-5450 2775)(-4850 2775);
WIRE 16 -1 (-5450 2825)(-4850 2825);
WIRE 16 -1 (-5450 2875)(-4850 2875);
WIRE 16 -1 (-5450 3075)(-4850 3075);
WIRE 16 -1 (-5175 3125)(-4850 3125);
WIRE 16 -1 (-5450 3175)(-4850 3175);
WIRE 16 -1 (-5175 3225)(-4850 3225);
WIRE 16 -1 (-5175 3275)(-4850 3275);
WIRE 16 -1 (-5450 3325)(-4850 3325);
WIRE 16 -1 (-5175 3375)(-4850 3375);
WIRE 16 -1 (-5175 3425)(-4850 3425);
WIRE 16 -1 (-5175 3475)(-4850 3475);
WIRE 16 -1 (-5450 3525)(-4850 3525);
WIRE 16 -1 (-5450 2075)(-4850 2075);
WIRE 16 -1 (-5175 2125)(-4850 2125);
WIRE 16 -1 (-5450 2175)(-4850 2175);
WIRE 16 -1 (-5450 2225)(-4850 2225);
WIRE 16 -1 (-5175 2275)(-4850 2275);
WIRE 16 -1 (-5450 2325)(-4850 2325);
WIRE 16 -1 (-5450 2375)(-4850 2375);
WIRE 16 -1 (-5450 2425)(-4850 2425);
WIRE 16 -1 (-5175 2475)(-4850 2475);
WIRE 16 -1 (-5175 2525)(-4850 2525);
WIRE 16 -1 (-3250 1575)(-2950 1575);
WIRE 16 -1 (-3250 1625)(-2950 1625);
WIRE 16 -1 (-2625 1675)(-3250 1675);
WIRE 16 -1 (-2625 1725)(-3250 1725);
WIRE 16 -1 (-2625 1775)(-3250 1775);
WIRE 16 -1 (-2950 1825)(-3250 1825);
WIRE 16 -1 (-2625 1875)(-3250 1875);
WIRE 16 -1 (-2625 1925)(-3250 1925);
WIRE 16 -1 (-3250 1975)(-2950 1975);
WIRE 16 -1 (-2625 2025)(-3250 2025);
WIRE 16 -1 (-2625 2625)(-3250 2625);
WIRE 16 -1 (-2625 2675)(-3250 2675);
WIRE 16 -1 (-3250 2725)(-2950 2725);
WIRE 16 -1 (-2950 2775)(-3250 2775);
WIRE 16 -1 (-2950 2825)(-3250 2825);
WIRE 16 -1 (-2625 2875)(-3250 2875);
WIRE 16 -1 (-2950 2925)(-3250 2925);
WIRE 16 -1 (-2950 2975)(-3250 2975);
WIRE 16 -1 (-2625 3025)(-3250 3025);
WIRE 16 -1 (-2950 3075)(-3250 3075);
WIRE 16 -1 (-2625 3125)(-3250 3125);
WIRE 16 -1 (-2625 3175)(-3250 3175);
WIRE 16 -1 (-2625 3275)(-3250 3275);
WIRE 16 -1 (-2625 3325)(-3250 3325);
WIRE 16 -1 (-2625 3375)(-3250 3375);
WIRE 16 -1 (-2625 3425)(-3250 3425);
WIRE 16 -1 (-2950 3475)(-3250 3475);
WIRE 16 -1 (-2950 3525)(-3250 3525);
WIRE 16 -1 (-2625 3575)(-3250 3575);
WIRE 16 -1 (-2950 2075)(-3250 2075);
WIRE 16 -1 (-2950 2125)(-3250 2125);
WIRE 16 -1 (-3250 2175)(-2950 2175);
WIRE 16 -1 (-3250 2225)(-2950 2225);
WIRE 16 -1 (-2950 2275)(-3250 2275);
WIRE 16 -1 (-3250 2325)(-2950 2325);
WIRE 16 -1 (-3250 2375)(-2950 2375);
WIRE 16 -1 (-2625 2425)(-3250 2425);
WIRE 16 -1 (-2625 2475)(-3250 2475);
WIRE 16 -1 (-3250 2525)(-2950 2525);
FORCENOTE
BOM_COST=PROC_SOCKET
(-7925 200) 0;
DISPLAY LEFT (-7925 200);
DISPLAY 1.723404 (-7925 200);
PAINT PURPLE (-7925 200);
FORCENOTE
ROOM=CPU1
(-7925 325) 0;
DISPLAY LEFT (-7925 325);
DISPLAY 1.723404 (-7925 325);
PAINT PURPLE (-7925 325);
QUIT
